FILE_TYPE = MACRO_DRAWING;
SET COLOR_WIRE YELLOW;
SET COLOR_PROP MONO;
SET COLOR_DOT WHITE;
SET COLOR_ARC YELLOW;
SET COLOR_BODY GREEN;
SET COLOR_NOTE MONO;
SET PROP_DISPLAY VALUE;
SET PAGE_NUMBER P227;
FORCEADD PVDDQ_KLM..1
(4350 2025);
FORCEPROP 3 LASTPIN (4350 1975) SIG_NAME PVDDQ_KLM\g
J 0
(4360 1985);
DISPLAY 0.659574 (4360 1985);
PAINT MONO (4360 1985);
DISPLAY INVISIBLE (4360 1985);
FORCEPROP 1 LAST HDL_POWER PVDDQ_KLM
J 1
(4350 2075);
DISPLAY 0.872340 (4350 2075);
PAINT GREEN (4350 2075);
DISPLAY INVISIBLE (4350 2075);
FORCEPROP 1 LAST BODY_TYPE PLUMBING
J 0
(4305 1982);
DISPLAY 0.340426 (4305 1982);
PAINT GREEN (4305 1982);
DISPLAY INVISIBLE (4305 1982);
FORCEPROP 1 LAST VOLTAGE 1.2V
J 0
(4305 1982);
DISPLAY 0.340426 (4305 1982);
PAINT SKYBLUE (4305 1982);
DISPLAY INVISIBLE (4305 1982);
FORCEPROP 1 LAST PATH I1
J 0
(4400 2050);
DISPLAY 0.872340 (4400 2050);
PAINT AQUA (4400 2050);
DISPLAY INVISIBLE (4400 2050);
FORCEPROP 2 LAST CDS_LIB mstr_symbols
J 0
(4350 2025);
PAINT ORANGE (4350 2025);
DISPLAY INVISIBLE (4350 2025);
FORCEADD IR354XX..1
(1825 2225);
FORCEPROP 1 LAST LOCATION EU1A2
J 0
(1375 3025);
DISPLAY 0.617021 (1375 3025);
PAINT AQUA (1375 3025);
FORCEPROP 2 LAST NO_XNET_CONNECTION 1
J 0
(1375 3075);
PAINT MONO (1375 3075);
FORCEPROP 1 LAST MATERIAL IC
J 0
(1375 2975);
DISPLAY 0.617021 (1375 2975);
PAINT SKYBLUE (1375 2975);
FORCEPROP 2 LASTPIN (2325 2775) $PN 38
J 0
(2335 2785);
DISPLAY 0.617021 (2335 2785);
PAINT ORANGE (2335 2785);
FORCEPROP 2 LASTPIN (1325 2225) $PN 6
J 2
(1315 2235);
DISPLAY 0.617021 (1315 2235);
PAINT ORANGE (1315 2235);
FORCEPROP 2 LASTPIN (2325 2275) $PN 36
J 0
(2335 2285);
DISPLAY 0.617021 (2335 2285);
PAINT ORANGE (2335 2285);
FORCEPROP 2 LASTPIN (1325 1925) $PN 33
J 2
(1315 1935);
DISPLAY 0.617021 (1315 1935);
PAINT ORANGE (1315 1935);
FORCEPROP 2 LASTPIN (2325 1725) $PN 7
J 0
(2335 1735);
DISPLAY 0.617021 (2335 1735);
PAINT ORANGE (2335 1735);
FORCEPROP 2 LASTPIN (1325 2375) $PN 1
J 2
(1315 2385);
DISPLAY 0.617021 (1315 2385);
PAINT ORANGE (1315 2385);
FORCEPROP 2 LASTPIN (1325 2575) $PN 4
J 2
(1315 2585);
DISPLAY 0.617021 (1315 2585);
PAINT ORANGE (1315 2585);
FORCEPROP 2 LASTPIN (1325 2475) $PN 35
J 2
(1315 2485);
DISPLAY 0.617021 (1315 2485);
PAINT ORANGE (1315 2485);
FORCEPROP 2 LASTPIN (1325 2725) $PN 30
J 2
(1315 2735);
DISPLAY 0.617021 (1315 2735);
PAINT ORANGE (1315 2735);
FORCEPROP 2 LASTPIN (1325 2775) $PN 3
J 2
(1315 2785);
DISPLAY 0.617021 (1315 2785);
PAINT ORANGE (1315 2785);
FORCEPROP 2 LASTPIN (2325 2575) $PN 37
J 0
(2335 2585);
DISPLAY 0.617021 (2335 2585);
PAINT ORANGE (2335 2585);
FORCEPROP 2 LASTPIN (1325 1875) $PN 32
J 2
(1315 1885);
DISPLAY 0.617021 (1315 1885);
PAINT ORANGE (1315 1885);
FORCEPROP 2 LASTPIN (2325 1825) $PN 2
J 0
(2335 1835);
DISPLAY 0.617021 (2335 1835);
PAINT ORANGE (2335 1835);
FORCEPROP 2 LASTPIN (2325 1775) $PN 40
J 0
(2335 1785);
DISPLAY 0.617021 (2335 1785);
PAINT ORANGE (2335 1785);
FORCEPROP 2 LASTPIN (1325 2275) $PN 41
J 2
(1315 2285);
DISPLAY 0.617021 (1315 2285);
PAINT ORANGE (1315 2285);
FORCEPROP 2 LASTPIN (1325 2675) $PN 25
J 2
(1315 2685);
DISPLAY 0.617021 (1315 2685);
PAINT ORANGE (1315 2685);
FORCEPROP 2 LASTPIN (1325 2125) $PN 34
J 2
(1315 2135);
DISPLAY 0.617021 (1315 2135);
PAINT ORANGE (1315 2135);
FORCEPROP 2 LASTPIN (2325 2525) $PN 31
J 0
(2335 2535);
DISPLAY 0.617021 (2335 2535);
PAINT ORANGE (2335 2535);
FORCEPROP 2 LASTPIN (1325 2025) $PN 39
J 2
(1315 2035);
DISPLAY 0.617021 (1315 2035);
PAINT ORANGE (1315 2035);
FORCEPROP 2 LASTPIN (2325 1675) $PN 5
J 0
(2335 1685);
DISPLAY 0.617021 (2335 1685);
PAINT ORANGE (2335 1685);
FORCEPROP 2 LASTPIN (2325 1925) $PN 10
J 0
(2335 1935);
DISPLAY 0.617021 (2335 1935);
PAINT ORANGE (2335 1935);
FORCEPROP 1 LAST PART_NUMBER H73688-001
J 0
(1425 1525);
DISPLAY 0.617021 (1425 1525);
PAINT BLUE (1425 1525);
FORCEPROP 1 LAST VALUE IR35411
J 1
(1825 2850);
DISPLAY 0.617021 (1825 2850);
PAINT SKYBLUE (1825 2850);
DISPLAY INVISIBLE (1825 2850);
FORCEPROP 2 LAST CDS_LIB mstr_discrete
J 0
(1825 2225);
PAINT ORANGE (1825 2225);
DISPLAY INVISIBLE (1825 2225);
FORCEPROP 1 LAST PACK_TYPE SM
J 0
(1375 3075);
PAINT SKYBLUE (1375 3075);
DISPLAY INVISIBLE (1375 3075);
FORCEPROP 2 LAST SEC_TYPE SM
J 0
(1375 3075);
DISPLAY 1.021277 (1375 3075);
PAINT ORANGE (1375 3075);
DISPLAY INVISIBLE (1375 3075);
FORCEPROP 2 LAST SEC 1
J 0
(1375 3075);
DISPLAY 0.680851 (1375 3075);
PAINT MONO (1375 3075);
DISPLAY INVISIBLE (1375 3075);
FORCEPROP 2 LAST CDS_LOCATION EU1A2
J 0
(1375 3025);
DISPLAY 0.617021 (1375 3025);
PAINT AQUA (1375 3025);
DISPLAY INVISIBLE (1375 3025);
FORCEPROP 1 LAST PATH I101
J 0
(1825 2975);
PAINT GREEN (1825 2975);
DISPLAY INVISIBLE (1825 2975);
FORCEADD IR354XX..1
(1825 -25);
FORCEPROP 0 LAST BOM_SS NOPOP
J 0
(1425 -750);
DISPLAY 0.638298 (1425 -750);
PAINT BROWN (1425 -750);
DISPLAY BOTH (1425 -750);
FORCEPROP 1 LAST PART_NUMBER H73688-001
J 0
(1425 -725);
DISPLAY 0.617021 (1425 -725);
PAINT BLUE (1425 -725);
FORCEPROP 2 LASTPIN (2325 275) $PN 31
J 0
(2335 285);
DISPLAY 0.617021 (2335 285);
PAINT ORANGE (2335 285);
FORCEPROP 2 LASTPIN (1325 475) $PN 30
J 2
(1315 485);
DISPLAY 0.617021 (1315 485);
PAINT ORANGE (1315 485);
FORCEPROP 2 LASTPIN (2325 25) $PN 36
J 0
(2335 35);
DISPLAY 0.617021 (2335 35);
PAINT ORANGE (2335 35);
FORCEPROP 2 LASTPIN (1325 -325) $PN 33
J 2
(1315 -315);
DISPLAY 0.617021 (1315 -315);
PAINT ORANGE (1315 -315);
FORCEPROP 2 LASTPIN (2325 -575) $PN 5
J 0
(2335 -565);
DISPLAY 0.617021 (2335 -565);
PAINT ORANGE (2335 -565);
FORCEPROP 2 LASTPIN (1325 -375) $PN 32
J 2
(1315 -365);
DISPLAY 0.617021 (1315 -365);
PAINT ORANGE (1315 -365);
FORCEPROP 2 LASTPIN (2325 -425) $PN 2
J 0
(2335 -415);
DISPLAY 0.617021 (2335 -415);
PAINT ORANGE (2335 -415);
FORCEPROP 2 LASTPIN (2325 -325) $PN 10
J 0
(2335 -315);
DISPLAY 0.617021 (2335 -315);
PAINT ORANGE (2335 -315);
FORCEPROP 2 LASTPIN (1325 225) $PN 35
J 2
(1315 235);
DISPLAY 0.617021 (1315 235);
PAINT ORANGE (1315 235);
FORCEPROP 2 LASTPIN (2325 525) $PN 38
J 0
(2335 535);
DISPLAY 0.617021 (2335 535);
PAINT ORANGE (2335 535);
FORCEPROP 2 LASTPIN (1325 425) $PN 25
J 2
(1315 435);
DISPLAY 0.617021 (1315 435);
PAINT ORANGE (1315 435);
FORCEPROP 2 LASTPIN (2325 -525) $PN 7
J 0
(2335 -515);
DISPLAY 0.617021 (2335 -515);
PAINT ORANGE (2335 -515);
FORCEPROP 1 LAST MATERIAL IC
J 0
(1375 725);
DISPLAY 0.617021 (1375 725);
PAINT SKYBLUE (1375 725);
FORCEPROP 2 LASTPIN (1325 25) $PN 41
J 2
(1315 35);
DISPLAY 0.617021 (1315 35);
PAINT ORANGE (1315 35);
FORCEPROP 2 LASTPIN (2325 -475) $PN 40
J 0
(2335 -465);
DISPLAY 0.617021 (2335 -465);
PAINT ORANGE (2335 -465);
FORCEPROP 2 LASTPIN (1325 525) $PN 3
J 2
(1315 535);
DISPLAY 0.617021 (1315 535);
PAINT ORANGE (1315 535);
FORCEPROP 2 LASTPIN (2325 325) $PN 37
J 0
(2335 335);
DISPLAY 0.617021 (2335 335);
PAINT ORANGE (2335 335);
FORCEPROP 2 LASTPIN (1325 125) $PN 1
J 2
(1315 135);
DISPLAY 0.617021 (1315 135);
PAINT ORANGE (1315 135);
FORCEPROP 1 LAST LOCATION EU1A1
J 0
(1375 775);
DISPLAY 0.617021 (1375 775);
PAINT AQUA (1375 775);
FORCEPROP 2 LASTPIN (1325 325) $PN 4
J 2
(1315 335);
DISPLAY 0.617021 (1315 335);
PAINT ORANGE (1315 335);
FORCEPROP 2 LASTPIN (1325 -25) $PN 6
J 2
(1315 -15);
DISPLAY 0.617021 (1315 -15);
PAINT ORANGE (1315 -15);
FORCEPROP 2 LASTPIN (1325 -225) $PN 39
J 2
(1315 -215);
DISPLAY 0.617021 (1315 -215);
PAINT ORANGE (1315 -215);
FORCEPROP 2 LAST NO_XNET_CONNECTION 1
J 0
(1375 825);
PAINT MONO (1375 825);
FORCEPROP 2 LASTPIN (1325 -125) $PN 34
J 2
(1315 -115);
DISPLAY 0.617021 (1315 -115);
PAINT ORANGE (1315 -115);
FORCEPROP 2 LAST CDS_LIB mstr_discrete
J 0
(1825 -25);
PAINT ORANGE (1825 -25);
DISPLAY INVISIBLE (1825 -25);
FORCEPROP 1 LAST PATH I102
J 0
(1825 725);
PAINT GREEN (1825 725);
DISPLAY INVISIBLE (1825 725);
FORCEPROP 2 LAST CDS_LOCATION EU1A1
J 0
(1375 775);
DISPLAY 0.617021 (1375 775);
PAINT AQUA (1375 775);
DISPLAY INVISIBLE (1375 775);
FORCEPROP 2 LAST SEC 1
J 0
(1375 825);
DISPLAY 0.680851 (1375 825);
PAINT MONO (1375 825);
DISPLAY INVISIBLE (1375 825);
FORCEPROP 2 LAST SEC_TYPE SM
J 0
(1375 825);
DISPLAY 1.021277 (1375 825);
PAINT ORANGE (1375 825);
DISPLAY INVISIBLE (1375 825);
FORCEPROP 1 LAST PACK_TYPE SM
J 0
(1375 825);
PAINT SKYBLUE (1375 825);
DISPLAY INVISIBLE (1375 825);
FORCEPROP 1 LAST VALUE IR35411
J 1
(1825 600);
DISPLAY 0.617021 (1825 600);
PAINT SKYBLUE (1825 600);
DISPLAY INVISIBLE (1825 600);
FORCEADD RES..2
(4650 2400);
FORCEPROP 1 LAST MATERIAL EMPTY
J 0
(4690 2325);
DISPLAY 0.617021 (4690 2325);
PAINT RED (4690 2325);
FORCEPROP 1 LAST PART_NUMBER G21796-187
J 0
(4690 2275);
DISPLAY 0.617021 (4690 2275);
PAINT BLUE (4690 2275);
FORCEPROP 1 LAST PACK_TYPE 0402
J 0
(4690 2225);
DISPLAY 0.617021 (4690 2225);
PAINT SKYBLUE (4690 2225);
FORCEPROP 1 LASTPIN (4650 2300) $PN 2
J 0
(4655 2310);
DISPLAY 0.617021 (4655 2310);
PAINT ORANGE (4655 2310);
FORCEPROP 1 LAST TOLERANCE 1%
J 0
(4695 2425);
DISPLAY 0.617021 (4695 2425);
PAINT SKYBLUE (4695 2425);
FORCEPROP 1 LAST LOCATION R1A3
J 0
(4695 2525);
DISPLAY 0.617021 (4695 2525);
PAINT AQUA (4695 2525);
FORCEPROP 1 LASTPIN (4650 2500) $PN 1
J 0
(4655 2462);
DISPLAY 0.617021 (4655 2462);
PAINT ORANGE (4655 2462);
FORCEPROP 1 LAST VALUE 68.1K
J 0
(4695 2475);
DISPLAY 0.617021 (4695 2475);
PAINT SKYBLUE (4695 2475);
FORCEPROP 1 LAST WATTAGE 1/16W
J 0
(4690 2375);
DISPLAY 0.617021 (4690 2375);
PAINT SKYBLUE (4690 2375);
FORCEPROP 2 LAST CDS_LIB mstr_discrete
J 0
(4650 2400);
PAINT ORANGE (4650 2400);
DISPLAY INVISIBLE (4650 2400);
FORCEPROP 1 LAST PATH I103
J 0
(4700 2575);
DISPLAY 0.978723 (4700 2575);
PAINT WHITE (4700 2575);
DISPLAY INVISIBLE (4700 2575);
FORCEPROP 2 LAST SEC 1
J 0
(4700 2625);
PAINT MONO (4700 2625);
DISPLAY INVISIBLE (4700 2625);
FORCEPROP 2 LAST SEC_TYPE 0402
J 0
(4700 2625);
DISPLAY 1.021277 (4700 2625);
PAINT ORANGE (4700 2625);
DISPLAY INVISIBLE (4700 2625);
FORCEADD GND..1
(4650 2200);
FORCEPROP 3 LASTPIN (4650 2250) SIG_NAME GND\g
J 0
(4660 2260);
DISPLAY 0.659574 (4660 2260);
PAINT MONO (4660 2260);
DISPLAY INVISIBLE (4660 2260);
FORCEPROP 1 LAST HDL_POWER GND
J 0
(4650 2350);
DISPLAY 1.723404 (4650 2350);
PAINT GREEN (4650 2350);
DISPLAY INVISIBLE (4650 2350);
FORCEPROP 1 LAST BODY_TYPE PLUMBING
J 0
(4605 2157);
DISPLAY 0.340426 (4605 2157);
PAINT GREEN (4605 2157);
DISPLAY INVISIBLE (4605 2157);
FORCEPROP 1 LAST VOLTAGE 0
J 0
(4650 2200);
PAINT SKYBLUE (4650 2200);
DISPLAY INVISIBLE (4650 2200);
FORCEPROP 2 LAST CDS_LIB mstr_symbols
J 0
(4650 2200);
PAINT ORANGE (4650 2200);
DISPLAY INVISIBLE (4650 2200);
FORCEPROP 1 LAST PATH I104
J 0
(4725 2200);
DISPLAY 0.872340 (4725 2200);
PAINT AQUA (4725 2200);
DISPLAY INVISIBLE (4725 2200);
FORCEPROP 1 LAST SIZE 1B
J 0
(4725 2150);
DISPLAY 1.723404 (4725 2150);
PAINT GREEN (4725 2150);
DISPLAY INVISIBLE (4725 2150);
FORCEPROP 2 LAST BOM_COST PROC_VRD_VCCIN_CPU0
J 0
(4275 2275);
DISPLAY 1.446809 (4275 2275);
PAINT MONO (4275 2275);
DISPLAY INVISIBLE (4275 2275);
FORCEPROP 2 LAST ROOM PVCCIN_CPU0_PWR_VR
J 0
(4100 2275);
DISPLAY 1.936170 (4100 2275);
PAINT ORANGE (4100 2275);
DISPLAY INVISIBLE (4100 2275);
FORCEADD RES..2
(4650 150);
FORCEPROP 1 LAST PACK_TYPE 0402
J 0
(4690 -25);
DISPLAY 0.617021 (4690 -25);
PAINT SKYBLUE (4690 -25);
FORCEPROP 1 LAST VALUE 68.1K
J 0
(4695 225);
DISPLAY 0.617021 (4695 225);
PAINT SKYBLUE (4695 225);
FORCEPROP 1 LASTPIN (4650 50) $PN 2
J 0
(4655 60);
DISPLAY 0.617021 (4655 60);
PAINT ORANGE (4655 60);
FORCEPROP 1 LAST TOLERANCE 1%
J 0
(4695 175);
DISPLAY 0.617021 (4695 175);
PAINT SKYBLUE (4695 175);
FORCEPROP 1 LASTPIN (4650 250) $PN 1
J 0
(4655 212);
DISPLAY 0.617021 (4655 212);
PAINT ORANGE (4655 212);
FORCEPROP 1 LAST MATERIAL EMPTY
J 0
(4690 75);
DISPLAY 0.617021 (4690 75);
PAINT RED (4690 75);
FORCEPROP 1 LAST WATTAGE 1/16W
J 0
(4690 125);
DISPLAY 0.617021 (4690 125);
PAINT SKYBLUE (4690 125);
FORCEPROP 1 LAST LOCATION R1A2
J 0
(4695 275);
DISPLAY 0.617021 (4695 275);
PAINT AQUA (4695 275);
FORCEPROP 0 LAST BOM_SS NOPOP
J 0
(4675 -75);
DISPLAY 0.638298 (4675 -75);
PAINT BROWN (4675 -75);
DISPLAY BOTH (4675 -75);
FORCEPROP 1 LAST PART_NUMBER G21796-187
J 0
(4690 25);
DISPLAY 0.617021 (4690 25);
PAINT BLUE (4690 25);
FORCEPROP 2 LAST CDS_LIB mstr_discrete
J 0
(4650 150);
PAINT ORANGE (4650 150);
DISPLAY INVISIBLE (4650 150);
FORCEPROP 1 LAST PATH I105
J 0
(4700 325);
DISPLAY 0.978723 (4700 325);
PAINT WHITE (4700 325);
DISPLAY INVISIBLE (4700 325);
FORCEPROP 2 LAST SEC 1
J 0
(4700 375);
PAINT MONO (4700 375);
DISPLAY INVISIBLE (4700 375);
FORCEPROP 2 LAST SEC_TYPE 0402
J 0
(4700 375);
DISPLAY 1.021277 (4700 375);
PAINT ORANGE (4700 375);
DISPLAY INVISIBLE (4700 375);
FORCEADD GND..1
(4650 -25);
FORCEPROP 3 LASTPIN (4650 25) SIG_NAME GND\g
J 0
(4660 35);
DISPLAY 0.659574 (4660 35);
PAINT MONO (4660 35);
DISPLAY INVISIBLE (4660 35);
FORCEPROP 2 LAST ROOM PVCCIN_CPU0_PWR_VR
J 0
(4100 50);
DISPLAY 1.936170 (4100 50);
PAINT ORANGE (4100 50);
DISPLAY INVISIBLE (4100 50);
FORCEPROP 2 LAST BOM_COST PROC_VRD_VCCIN_CPU0
J 0
(4275 50);
DISPLAY 1.446809 (4275 50);
PAINT MONO (4275 50);
DISPLAY INVISIBLE (4275 50);
FORCEPROP 2 LAST CDS_LIB mstr_symbols
J 0
(4650 -25);
PAINT ORANGE (4650 -25);
DISPLAY INVISIBLE (4650 -25);
FORCEPROP 1 LAST VOLTAGE 0
J 0
(4650 -25);
PAINT SKYBLUE (4650 -25);
DISPLAY INVISIBLE (4650 -25);
FORCEPROP 1 LAST PATH I106
J 0
(4725 -25);
DISPLAY 0.872340 (4725 -25);
PAINT AQUA (4725 -25);
DISPLAY INVISIBLE (4725 -25);
FORCEPROP 1 LAST SIZE 1B
J 0
(4725 -75);
DISPLAY 1.723404 (4725 -75);
PAINT GREEN (4725 -75);
DISPLAY INVISIBLE (4725 -75);
FORCEPROP 1 LAST BODY_TYPE PLUMBING
J 0
(4605 -68);
DISPLAY 0.340426 (4605 -68);
PAINT GREEN (4605 -68);
DISPLAY INVISIBLE (4605 -68);
FORCEPROP 1 LAST HDL_POWER GND
J 0
(4650 125);
DISPLAY 1.723404 (4650 125);
PAINT GREEN (4650 125);
DISPLAY INVISIBLE (4650 125);
FORCEADD P5V_STBY..1
(600 3200);
FORCEPROP 3 LASTPIN (600 3150) SIG_NAME P5V_STBY\g
J 0
(610 3160);
DISPLAY 0.659574 (610 3160);
PAINT MONO (610 3160);
DISPLAY INVISIBLE (610 3160);
FORCEPROP 1 LAST HDL_POWER P5V_STBY
J 0
(300 3075);
DISPLAY 0.872340 (300 3075);
PAINT ORANGE (300 3075);
DISPLAY INVISIBLE (300 3075);
FORCEPROP 1 LAST BODY_TYPE PLUMBING
J 0
(555 3157);
DISPLAY 0.340426 (555 3157);
PAINT GREEN (555 3157);
DISPLAY INVISIBLE (555 3157);
FORCEPROP 1 LAST VOLTAGE 5.0V
J 0
(555 3157);
DISPLAY 0.340426 (555 3157);
PAINT SKYBLUE (555 3157);
DISPLAY INVISIBLE (555 3157);
FORCEPROP 2 LAST CDS_LIB mstr_symbols
J 0
(600 3200);
PAINT ORANGE (600 3200);
DISPLAY INVISIBLE (600 3200);
FORCEPROP 1 LAST SIZE 1B
J 0
(645 3222);
DISPLAY 0.340426 (645 3222);
PAINT GREEN (645 3222);
DISPLAY INVISIBLE (645 3222);
FORCEPROP 1 LAST PATH I107
J 0
(645 3202);
DISPLAY 0.340426 (645 3202);
PAINT GREEN (645 3202);
DISPLAY INVISIBLE (645 3202);
FORCEADD CAP_A..1
(1150 1725);
FORCEPROP 1 LAST PART_NUMBER A36096-030
J 0
(1200 1575);
DISPLAY 0.617021 (1200 1575);
PAINT BLUE (1200 1575);
FORCEPROP 1 LASTPIN (1150 1625) $PN 2
J 0
(1160 1605);
DISPLAY 0.787234 (1160 1605);
PAINT ORANGE (1160 1605);
FORCEPROP 1 LAST TOLERANCE 10%
J 0
(1200 1675);
DISPLAY 0.617021 (1200 1675);
PAINT SKYBLUE (1200 1675);
FORCEPROP 1 LAST PACK_TYPE 0402V
J 0
(1200 1525);
DISPLAY 0.617021 (1200 1525);
PAINT SKYBLUE (1200 1525);
FORCEPROP 1 LAST VOLTAGE 16V
J 0
(1200 1725);
DISPLAY 0.617021 (1200 1725);
PAINT SKYBLUE (1200 1725);
FORCEPROP 1 LAST LOCATION CT7
J 0
(1000 1725);
DISPLAY 0.617021 (1000 1725);
PAINT AQUA (1000 1725);
FORCEPROP 1 LAST VALUE 0.1UF
J 0
(1200 1775);
DISPLAY 0.617021 (1200 1775);
PAINT SKYBLUE (1200 1775);
FORCEPROP 1 LASTPIN (1150 1825) $PN 1
J 0
(1160 1805);
DISPLAY 0.787234 (1160 1805);
PAINT ORANGE (1160 1805);
FORCEPROP 1 LAST MATERIAL X7R
J 0
(1200 1625);
DISPLAY 0.617021 (1200 1625);
PAINT SKYBLUE (1200 1625);
FORCEPROP 0 LAST POP NOPOP
J 0
(1200 1474);
DISPLAY 1.021277 (1200 1474);
PAINT RED (1200 1474);
FORCEPROP 2 LAST ROOM PVCCIN_CPU0_PWR_VR
J 0
(1200 1875);
DISPLAY 1.361702 (1200 1875);
PAINT ORANGE (1200 1875);
DISPLAY INVISIBLE (1200 1875);
FORCEPROP 1 LAST PATH I109
J 0
(1200 1875);
DISPLAY 0.978723 (1200 1875);
PAINT WHITE (1200 1875);
DISPLAY INVISIBLE (1200 1875);
FORCEPROP 2 LAST CDS_LIB dev_discrete
J 0
(1150 1725);
PAINT MONO (1150 1725);
DISPLAY INVISIBLE (1150 1725);
FORCEPROP 0 LAST SEC 1
J 0
(1200 1825);
DISPLAY 0.680851 (1200 1825);
PAINT MONO (1200 1825);
DISPLAY INVISIBLE (1200 1825);
FORCEPROP 2 LAST SEC_TYPE 0402V
J 0
(1200 1925);
DISPLAY 1.021277 (1200 1925);
PAINT ORANGE (1200 1925);
DISPLAY INVISIBLE (1200 1925);
FORCEADD GND..1
(1150 1475);
FORCEPROP 3 LASTPIN (1150 1525) SIG_NAME GND\g
J 0
(1160 1535);
DISPLAY 0.659574 (1160 1535);
PAINT MONO (1160 1535);
DISPLAY INVISIBLE (1160 1535);
FORCEPROP 1 LAST HDL_POWER GND
J 0
(1150 1625);
DISPLAY 1.723404 (1150 1625);
PAINT GREEN (1150 1625);
DISPLAY INVISIBLE (1150 1625);
FORCEPROP 1 LAST BODY_TYPE PLUMBING
J 0
(1105 1432);
DISPLAY 0.340426 (1105 1432);
PAINT GREEN (1105 1432);
DISPLAY INVISIBLE (1105 1432);
FORCEPROP 2 LAST ROOM PVCCIN_CPU0_PWR_VR
J 0
(600 1550);
DISPLAY 1.936170 (600 1550);
PAINT ORANGE (600 1550);
DISPLAY INVISIBLE (600 1550);
FORCEPROP 2 LAST BOM_COST PROC_VRD_VCCIN_CPU0
J 0
(775 1550);
DISPLAY 1.446809 (775 1550);
PAINT MONO (775 1550);
DISPLAY INVISIBLE (775 1550);
FORCEPROP 1 LAST SIZE 1B
J 0
(1225 1425);
DISPLAY 1.723404 (1225 1425);
PAINT GREEN (1225 1425);
DISPLAY INVISIBLE (1225 1425);
FORCEPROP 1 LAST VOLTAGE 0
J 0
(1150 1475);
PAINT SKYBLUE (1150 1475);
DISPLAY INVISIBLE (1150 1475);
FORCEPROP 1 LAST PATH I110
J 0
(1225 1475);
DISPLAY 0.872340 (1225 1475);
PAINT AQUA (1225 1475);
DISPLAY INVISIBLE (1225 1475);
FORCEPROP 2 LAST CDS_LIB mstr_symbols
J 0
(1150 1475);
PAINT MONO (1150 1475);
DISPLAY INVISIBLE (1150 1475);
FORCEADD GND..1
(2825 1125);
FORCEPROP 3 LASTPIN (2825 1175) SIG_NAME GND\g
J 0
(2835 1185);
DISPLAY 0.659574 (2835 1185);
PAINT MONO (2835 1185);
DISPLAY INVISIBLE (2835 1185);
FORCEPROP 1 LAST HDL_POWER GND
J 0
(2825 1275);
DISPLAY 1.723404 (2825 1275);
PAINT GREEN (2825 1275);
DISPLAY INVISIBLE (2825 1275);
FORCEPROP 1 LAST BODY_TYPE PLUMBING
J 0
(2780 1082);
DISPLAY 0.340426 (2780 1082);
PAINT GREEN (2780 1082);
DISPLAY INVISIBLE (2780 1082);
FORCEPROP 2 LAST CDS_LIB mstr_symbols
J 0
(2825 1125);
PAINT MONO (2825 1125);
DISPLAY INVISIBLE (2825 1125);
FORCEPROP 1 LAST PATH I113
J 0
(2900 1125);
DISPLAY 0.872340 (2900 1125);
PAINT AQUA (2900 1125);
DISPLAY INVISIBLE (2900 1125);
FORCEPROP 1 LAST SIZE 1B
J 0
(2900 1075);
DISPLAY 1.723404 (2900 1075);
PAINT GREEN (2900 1075);
DISPLAY INVISIBLE (2900 1075);
FORCEPROP 1 LAST VOLTAGE 0
J 0
(2825 1125);
PAINT SKYBLUE (2825 1125);
DISPLAY INVISIBLE (2825 1125);
FORCEPROP 2 LAST BOM_COST PROC_VRD_VCCIN_CPU0
J 0
(2450 1200);
DISPLAY 1.446809 (2450 1200);
PAINT MONO (2450 1200);
DISPLAY INVISIBLE (2450 1200);
FORCEPROP 2 LAST ROOM PVCCIN_CPU0_PWR_VR
J 0
(2275 1200);
DISPLAY 1.936170 (2275 1200);
PAINT ORANGE (2275 1200);
DISPLAY INVISIBLE (2275 1200);
FORCEADD CAP..1
(3050 2200);
FORCEPROP 0 LAST POP NOPOP
J 0
(3250 2225);
DISPLAY 1.021277 (3250 2225);
PAINT RED (3250 2225);
FORCEPROP 1 LAST VALUE 1000PF
J 0
(3100 2250);
DISPLAY 0.617021 (3100 2250);
PAINT SKYBLUE (3100 2250);
FORCEPROP 1 LAST LOCATION CT8
J 0
(2975 2250);
DISPLAY 0.617021 (2975 2250);
PAINT AQUA (2975 2250);
FORCEPROP 1 LASTPIN (3050 2300) $PN 1
J 0
(3060 2280);
DISPLAY 0.787234 (3060 2280);
PAINT ORANGE (3060 2280);
FORCEPROP 1 LASTPIN (3050 2100) $PN 2
J 0
(3060 2080);
DISPLAY 0.787234 (3060 2080);
PAINT ORANGE (3060 2080);
FORCEPROP 1 LAST VOLTAGE 50V
J 0
(3100 2200);
DISPLAY 0.617021 (3100 2200);
PAINT SKYBLUE (3100 2200);
FORCEPROP 1 LAST TOLERANCE 10%
J 0
(3100 2150);
DISPLAY 0.617021 (3100 2150);
PAINT SKYBLUE (3100 2150);
FORCEPROP 1 LAST MATERIAL X7R
J 0
(3100 2100);
DISPLAY 0.617021 (3100 2100);
PAINT SKYBLUE (3100 2100);
FORCEPROP 1 LAST PART_NUMBER A36096-046
J 0
(3100 2050);
DISPLAY 0.617021 (3100 2050);
PAINT BLUE (3100 2050);
FORCEPROP 1 LAST PACK_TYPE 0402LF
J 0
(3100 2000);
DISPLAY 0.617021 (3100 2000);
PAINT SKYBLUE (3100 2000);
FORCEPROP 2 LAST CDS_LIB mstr_discrete
J 0
(3050 2200);
PAINT MONO (3050 2200);
DISPLAY INVISIBLE (3050 2200);
FORCEPROP 1 LAST PATH I114
J 0
(3100 2350);
DISPLAY 0.978723 (3100 2350);
PAINT WHITE (3100 2350);
DISPLAY INVISIBLE (3100 2350);
FORCEPROP 0 LAST ROOM VDDQ_KLM_PWR_VR
J 0
(3100 2400);
DISPLAY 1.021277 (3100 2400);
PAINT ORANGE (3100 2400);
DISPLAY INVISIBLE (3100 2400);
FORCEPROP 0 LAST SEC 1
J 0
(3100 2300);
DISPLAY 0.680851 (3100 2300);
PAINT MONO (3100 2300);
DISPLAY INVISIBLE (3100 2300);
FORCEPROP 2 LAST SEC_TYPE 0402LF
J 0
(3100 2400);
DISPLAY 1.021277 (3100 2400);
PAINT ORANGE (3100 2400);
DISPLAY INVISIBLE (3100 2400);
FORCEADD GND..1
(3050 2000);
FORCEPROP 3 LASTPIN (3050 2050) SIG_NAME GND\g
J 0
(3060 2060);
DISPLAY 0.659574 (3060 2060);
PAINT MONO (3060 2060);
DISPLAY INVISIBLE (3060 2060);
FORCEPROP 1 LAST HDL_POWER GND
J 0
(3050 2150);
DISPLAY 1.170213 (3050 2150);
PAINT GREEN (3050 2150);
DISPLAY INVISIBLE (3050 2150);
FORCEPROP 1 LAST BODY_TYPE PLUMBING
J 0
(3005 1957);
DISPLAY 0.340426 (3005 1957);
PAINT GREEN (3005 1957);
DISPLAY INVISIBLE (3005 1957);
FORCEPROP 2 LAST CDS_LIB mstr_symbols
J 0
(3050 2000);
PAINT MONO (3050 2000);
DISPLAY INVISIBLE (3050 2000);
FORCEPROP 1 LAST PATH I115
J 0
(3125 2000);
DISPLAY 0.872340 (3125 2000);
PAINT AQUA (3125 2000);
DISPLAY INVISIBLE (3125 2000);
FORCEPROP 2 LAST ROOM VDDQ_KLM_PWR_VR
J 0
(2475 2075);
DISPLAY 1.361702 (2475 2075);
PAINT ORANGE (2475 2075);
DISPLAY INVISIBLE (2475 2075);
FORCEPROP 1 LAST VOLTAGE 0
J 0
(3050 2000);
PAINT SKYBLUE (3050 2000);
DISPLAY INVISIBLE (3050 2000);
FORCEPROP 1 LAST SIZE 1B
J 0
(3125 1950);
DISPLAY 1.170213 (3125 1950);
PAINT AQUA (3125 1950);
DISPLAY INVISIBLE (3125 1950);
FORCEADD GND..1
(2925 -1000);
FORCEPROP 3 LASTPIN (2925 -950) SIG_NAME GND\g
J 0
(2935 -940);
DISPLAY 0.659574 (2935 -940);
PAINT MONO (2935 -940);
DISPLAY INVISIBLE (2935 -940);
FORCEPROP 2 LAST CDS_LIB mstr_symbols
J 0
(2925 -1000);
PAINT MONO (2925 -1000);
DISPLAY INVISIBLE (2925 -1000);
FORCEPROP 1 LAST PATH I117
J 0
(3000 -1000);
DISPLAY 0.872340 (3000 -1000);
PAINT AQUA (3000 -1000);
DISPLAY INVISIBLE (3000 -1000);
FORCEPROP 1 LAST SIZE 1B
J 0
(3000 -1050);
DISPLAY 1.723404 (3000 -1050);
PAINT GREEN (3000 -1050);
DISPLAY INVISIBLE (3000 -1050);
FORCEPROP 1 LAST VOLTAGE 0
J 0
(2925 -1000);
PAINT SKYBLUE (2925 -1000);
DISPLAY INVISIBLE (2925 -1000);
FORCEPROP 2 LAST BOM_COST PROC_VRD_VCCIN_CPU0
J 0
(2550 -925);
DISPLAY 1.446809 (2550 -925);
PAINT MONO (2550 -925);
DISPLAY INVISIBLE (2550 -925);
FORCEPROP 2 LAST ROOM PVCCIN_CPU0_PWR_VR
J 0
(2375 -925);
DISPLAY 1.936170 (2375 -925);
PAINT ORANGE (2375 -925);
DISPLAY INVISIBLE (2375 -925);
FORCEPROP 1 LAST BODY_TYPE PLUMBING
J 0
(2880 -1043);
DISPLAY 0.340426 (2880 -1043);
PAINT GREEN (2880 -1043);
DISPLAY INVISIBLE (2880 -1043);
FORCEPROP 1 LAST HDL_POWER GND
J 0
(2925 -850);
DISPLAY 1.723404 (2925 -850);
PAINT GREEN (2925 -850);
DISPLAY INVISIBLE (2925 -850);
FORCEADD CAP..1
(2950 25);
FORCEPROP 0 LAST BOM_SS NOPOP
J 0
(3125 -25);
DISPLAY 0.638298 (3125 -25);
PAINT BROWN (3125 -25);
DISPLAY BOTH (3125 -25);
FORCEPROP 1 LAST PACK_TYPE 0402LF
J 0
(3000 -175);
DISPLAY 0.617021 (3000 -175);
PAINT SKYBLUE (3000 -175);
FORCEPROP 1 LASTPIN (2950 125) $PN 1
J 0
(2960 105);
DISPLAY 0.787234 (2960 105);
PAINT ORANGE (2960 105);
FORCEPROP 1 LAST VALUE 1000PF
J 0
(3000 75);
DISPLAY 0.617021 (3000 75);
PAINT SKYBLUE (3000 75);
FORCEPROP 1 LAST VOLTAGE 50V
J 0
(3000 25);
DISPLAY 0.617021 (3000 25);
PAINT SKYBLUE (3000 25);
FORCEPROP 1 LAST TOLERANCE 10%
J 0
(3000 -25);
DISPLAY 0.617021 (3000 -25);
PAINT SKYBLUE (3000 -25);
FORCEPROP 1 LAST MATERIAL X7R
J 0
(3000 -75);
DISPLAY 0.617021 (3000 -75);
PAINT SKYBLUE (3000 -75);
FORCEPROP 1 LASTPIN (2950 -75) $PN 2
J 0
(2960 -95);
DISPLAY 0.787234 (2960 -95);
PAINT ORANGE (2960 -95);
FORCEPROP 1 LAST LOCATION CT10
J 0
(2800 25);
DISPLAY 0.617021 (2800 25);
PAINT AQUA (2800 25);
FORCEPROP 1 LAST PART_NUMBER A36096-046
J 0
(3000 -125);
DISPLAY 0.617021 (3000 -125);
PAINT BLUE (3000 -125);
FORCEPROP 0 LAST POP NOPOP
J 0
(2725 -50);
DISPLAY 1.021277 (2725 -50);
PAINT RED (2725 -50);
FORCEPROP 2 LAST SEC_TYPE 0402LF
J 0
(3000 225);
DISPLAY 1.021277 (3000 225);
PAINT ORANGE (3000 225);
DISPLAY INVISIBLE (3000 225);
FORCEPROP 0 LAST SEC 1
J 0
(3000 125);
DISPLAY 0.680851 (3000 125);
PAINT MONO (3000 125);
DISPLAY INVISIBLE (3000 125);
FORCEPROP 2 LAST CDS_LIB mstr_discrete
J 0
(2950 25);
PAINT MONO (2950 25);
DISPLAY INVISIBLE (2950 25);
FORCEPROP 1 LAST PATH I119
J 0
(3000 175);
DISPLAY 0.978723 (3000 175);
PAINT WHITE (3000 175);
DISPLAY INVISIBLE (3000 175);
FORCEPROP 0 LAST ROOM VDDQ_KLM_PWR_VR
J 0
(3000 225);
DISPLAY 1.021277 (3000 225);
PAINT ORANGE (3000 225);
DISPLAY INVISIBLE (3000 225);
FORCEADD GND..1
(2950 -175);
FORCEPROP 3 LASTPIN (2950 -125) SIG_NAME GND\g
J 0
(2960 -115);
DISPLAY 0.659574 (2960 -115);
PAINT MONO (2960 -115);
DISPLAY INVISIBLE (2960 -115);
FORCEPROP 2 LAST CDS_LIB mstr_symbols
J 0
(2950 -175);
PAINT MONO (2950 -175);
DISPLAY INVISIBLE (2950 -175);
FORCEPROP 1 LAST PATH I120
J 0
(3025 -175);
DISPLAY 0.872340 (3025 -175);
PAINT AQUA (3025 -175);
DISPLAY INVISIBLE (3025 -175);
FORCEPROP 2 LAST ROOM VDDQ_KLM_PWR_VR
J 0
(2375 -100);
DISPLAY 1.361702 (2375 -100);
PAINT ORANGE (2375 -100);
DISPLAY INVISIBLE (2375 -100);
FORCEPROP 1 LAST VOLTAGE 0
J 0
(2950 -175);
PAINT SKYBLUE (2950 -175);
DISPLAY INVISIBLE (2950 -175);
FORCEPROP 1 LAST SIZE 1B
J 0
(3025 -225);
DISPLAY 1.170213 (3025 -225);
PAINT AQUA (3025 -225);
DISPLAY INVISIBLE (3025 -225);
FORCEPROP 1 LAST BODY_TYPE PLUMBING
J 0
(2905 -218);
DISPLAY 0.340426 (2905 -218);
PAINT GREEN (2905 -218);
DISPLAY INVISIBLE (2905 -218);
FORCEPROP 1 LAST HDL_POWER GND
J 0
(2950 -25);
DISPLAY 1.170213 (2950 -25);
PAINT GREEN (2950 -25);
DISPLAY INVISIBLE (2950 -25);
FORCEADD CAP_A..1
(1150 -800);
FORCEPROP 0 LAST BOM_SS NOPOP
J 0
(1475 -1025);
DISPLAY 0.638298 (1475 -1025);
PAINT BROWN (1475 -1025);
DISPLAY BOTH (1475 -1025);
FORCEPROP 0 LAST POP NOPOP
J 0
(1230 -1057);
DISPLAY 1.021277 (1230 -1057);
PAINT RED (1230 -1057);
FORCEPROP 1 LAST PACK_TYPE 0402V
J 0
(1200 -1000);
DISPLAY 0.617021 (1200 -1000);
PAINT SKYBLUE (1200 -1000);
FORCEPROP 1 LAST PART_NUMBER A36096-030
J 0
(1200 -950);
DISPLAY 0.617021 (1200 -950);
PAINT BLUE (1200 -950);
FORCEPROP 1 LAST MATERIAL X7R
J 0
(1200 -900);
DISPLAY 0.617021 (1200 -900);
PAINT SKYBLUE (1200 -900);
FORCEPROP 1 LAST VALUE 0.1UF
J 0
(1200 -750);
DISPLAY 0.617021 (1200 -750);
PAINT SKYBLUE (1200 -750);
FORCEPROP 1 LAST VOLTAGE 16V
J 0
(1200 -800);
DISPLAY 0.617021 (1200 -800);
PAINT SKYBLUE (1200 -800);
FORCEPROP 1 LAST TOLERANCE 10%
J 0
(1200 -850);
DISPLAY 0.617021 (1200 -850);
PAINT SKYBLUE (1200 -850);
FORCEPROP 1 LAST LOCATION CT12
J 0
(1000 -800);
DISPLAY 0.617021 (1000 -800);
PAINT AQUA (1000 -800);
FORCEPROP 1 LASTPIN (1150 -900) $PN 2
J 0
(1160 -920);
DISPLAY 0.787234 (1160 -920);
PAINT ORANGE (1160 -920);
FORCEPROP 1 LASTPIN (1150 -700) $PN 1
J 0
(1160 -720);
DISPLAY 0.787234 (1160 -720);
PAINT ORANGE (1160 -720);
FORCEPROP 0 LAST SEC 1
J 0
(1200 -700);
DISPLAY 0.680851 (1200 -700);
PAINT MONO (1200 -700);
DISPLAY INVISIBLE (1200 -700);
FORCEPROP 2 LAST SEC_TYPE 0402V
J 0
(1200 -600);
DISPLAY 1.021277 (1200 -600);
PAINT ORANGE (1200 -600);
DISPLAY INVISIBLE (1200 -600);
FORCEPROP 2 LAST ROOM PVCCIN_CPU0_PWR_VR
J 0
(1200 -650);
DISPLAY 1.361702 (1200 -650);
PAINT ORANGE (1200 -650);
DISPLAY INVISIBLE (1200 -650);
FORCEPROP 1 LAST PATH I122
J 0
(1200 -650);
DISPLAY 0.978723 (1200 -650);
PAINT WHITE (1200 -650);
DISPLAY INVISIBLE (1200 -650);
FORCEPROP 2 LAST CDS_LIB dev_discrete
J 0
(1150 -800);
PAINT MONO (1150 -800);
DISPLAY INVISIBLE (1150 -800);
FORCEADD GND..1
(1150 -1000);
FORCEPROP 3 LASTPIN (1150 -950) SIG_NAME GND\g
J 0
(1160 -940);
DISPLAY 0.659574 (1160 -940);
PAINT MONO (1160 -940);
DISPLAY INVISIBLE (1160 -940);
FORCEPROP 2 LAST ROOM PVCCIN_CPU0_PWR_VR
J 0
(600 -925);
DISPLAY 1.936170 (600 -925);
PAINT ORANGE (600 -925);
DISPLAY INVISIBLE (600 -925);
FORCEPROP 2 LAST BOM_COST PROC_VRD_VCCIN_CPU0
J 0
(775 -925);
DISPLAY 1.446809 (775 -925);
PAINT MONO (775 -925);
DISPLAY INVISIBLE (775 -925);
FORCEPROP 1 LAST SIZE 1B
J 0
(1225 -1050);
DISPLAY 1.723404 (1225 -1050);
PAINT GREEN (1225 -1050);
DISPLAY INVISIBLE (1225 -1050);
FORCEPROP 1 LAST VOLTAGE 0
J 0
(1150 -1000);
PAINT SKYBLUE (1150 -1000);
DISPLAY INVISIBLE (1150 -1000);
FORCEPROP 1 LAST PATH I123
J 0
(1225 -1000);
DISPLAY 0.872340 (1225 -1000);
PAINT AQUA (1225 -1000);
DISPLAY INVISIBLE (1225 -1000);
FORCEPROP 2 LAST CDS_LIB mstr_symbols
J 0
(1150 -1000);
PAINT MONO (1150 -1000);
DISPLAY INVISIBLE (1150 -1000);
FORCEPROP 1 LAST BODY_TYPE PLUMBING
J 0
(1105 -1043);
DISPLAY 0.340426 (1105 -1043);
PAINT GREEN (1105 -1043);
DISPLAY INVISIBLE (1105 -1043);
FORCEPROP 1 LAST HDL_POWER GND
J 0
(1150 -850);
DISPLAY 1.723404 (1150 -850);
PAINT GREEN (1150 -850);
DISPLAY INVISIBLE (1150 -850);
FORCEADD CAP..1
(2825 1750);
FORCEPROP 0 LAST POP NOPOP
J 0
(3025 1650);
DISPLAY 0.808511 (3025 1650);
PAINT RED (3025 1650);
FORCEPROP 1 LAST PART_NUMBER A36096-046
J 0
(3100 1725);
DISPLAY 0.617021 (3100 1725);
PAINT BLUE (3100 1725);
FORCEPROP 1 LAST VOLTAGE 50V
J 0
(3175 1800);
DISPLAY 0.617021 (3175 1800);
PAINT SKYBLUE (3175 1800);
FORCEPROP 1 LAST VALUE 1000PF
J 0
(3000 1800);
DISPLAY 0.617021 (3000 1800);
PAINT SKYBLUE (3000 1800);
FORCEPROP 1 LAST MATERIAL X7R
J 0
(3000 1725);
DISPLAY 0.617021 (3000 1725);
PAINT SKYBLUE (3000 1725);
FORCEPROP 1 LAST PACK_TYPE 0402LF
J 0
(2875 1650);
DISPLAY 0.617021 (2875 1650);
PAINT SKYBLUE (2875 1650);
FORCEPROP 1 LAST TOLERANCE 10%
J 0
(2875 1725);
DISPLAY 0.617021 (2875 1725);
PAINT SKYBLUE (2875 1725);
FORCEPROP 1 LASTPIN (2825 1850) $PN 1
J 0
(2835 1830);
DISPLAY 0.787234 (2835 1830);
PAINT ORANGE (2835 1830);
FORCEPROP 1 LASTPIN (2825 1650) $PN 2
J 0
(2835 1630);
DISPLAY 0.787234 (2835 1630);
PAINT ORANGE (2835 1630);
FORCEPROP 1 LAST LOCATION CT9
J 0
(2875 1800);
DISPLAY 0.617021 (2875 1800);
PAINT AQUA (2875 1800);
FORCEPROP 2 LAST CDS_LIB mstr_discrete
J 0
(2825 1750);
PAINT MONO (2825 1750);
DISPLAY INVISIBLE (2825 1750);
FORCEPROP 1 LAST PATH I134
J 0
(2875 1900);
DISPLAY 0.978723 (2875 1900);
PAINT WHITE (2875 1900);
DISPLAY INVISIBLE (2875 1900);
FORCEPROP 0 LAST ROOM VDDQ_KLM_PWR_VR
J 0
(2875 1950);
DISPLAY 1.021277 (2875 1950);
PAINT ORANGE (2875 1950);
DISPLAY INVISIBLE (2875 1950);
FORCEPROP 0 LAST SEC 1
J 0
(2875 1900);
DISPLAY 0.680851 (2875 1900);
PAINT MONO (2875 1900);
DISPLAY INVISIBLE (2875 1900);
FORCEPROP 2 LAST SEC_TYPE 0402LF
J 0
(2875 1950);
DISPLAY 1.021277 (2875 1950);
PAINT ORANGE (2875 1950);
DISPLAY INVISIBLE (2875 1950);
FORCEADD CAP..1
(2925 -475);
FORCEPROP 1 LAST LOCATION CT11
J 0
(2975 -425);
DISPLAY 0.617021 (2975 -425);
PAINT AQUA (2975 -425);
FORCEPROP 1 LASTPIN (2925 -575) $PN 2
J 0
(2935 -595);
DISPLAY 0.787234 (2935 -595);
PAINT ORANGE (2935 -595);
FORCEPROP 1 LASTPIN (2925 -375) $PN 1
J 0
(2935 -395);
DISPLAY 0.787234 (2935 -395);
PAINT ORANGE (2935 -395);
FORCEPROP 1 LAST TOLERANCE 10%
J 0
(3275 -425);
DISPLAY 0.617021 (3275 -425);
PAINT SKYBLUE (3275 -425);
FORCEPROP 1 LAST VOLTAGE 50V
J 0
(2975 -475);
DISPLAY 0.617021 (2975 -475);
PAINT SKYBLUE (2975 -475);
FORCEPROP 1 LAST VALUE 1000PF
J 0
(3100 -425);
DISPLAY 0.617021 (3100 -425);
PAINT SKYBLUE (3100 -425);
FORCEPROP 1 LAST MATERIAL X7R
J 0
(3075 -475);
DISPLAY 0.617021 (3075 -475);
PAINT SKYBLUE (3075 -475);
FORCEPROP 1 LAST PACK_TYPE 0402LF
J 0
(3150 -525);
DISPLAY 0.617021 (3150 -525);
PAINT SKYBLUE (3150 -525);
FORCEPROP 0 LAST BOM_SS NOPOP
J 0
(3150 -575);
DISPLAY 0.638298 (3150 -575);
PAINT BROWN (3150 -575);
DISPLAY BOTH (3150 -575);
FORCEPROP 1 LAST PART_NUMBER A36096-046
J 0
(3175 -475);
DISPLAY 0.617021 (3175 -475);
PAINT BLUE (3175 -475);
FORCEPROP 0 LAST POP NOPOP
J 0
(2975 -525);
DISPLAY 0.638298 (2975 -525);
PAINT RED (2975 -525);
FORCEPROP 2 LAST SEC_TYPE 0402LF
J 0
(2975 -275);
DISPLAY 1.021277 (2975 -275);
PAINT ORANGE (2975 -275);
DISPLAY INVISIBLE (2975 -275);
FORCEPROP 0 LAST SEC 1
J 0
(2975 -325);
DISPLAY 0.680851 (2975 -325);
PAINT MONO (2975 -325);
DISPLAY INVISIBLE (2975 -325);
FORCEPROP 0 LAST ROOM VDDQ_KLM_PWR_VR
J 0
(2975 -275);
DISPLAY 1.021277 (2975 -275);
PAINT ORANGE (2975 -275);
DISPLAY INVISIBLE (2975 -275);
FORCEPROP 1 LAST PATH I135
J 0
(2975 -325);
DISPLAY 0.978723 (2975 -325);
PAINT WHITE (2975 -325);
DISPLAY INVISIBLE (2975 -325);
FORCEPROP 2 LAST CDS_LIB mstr_discrete
J 0
(2925 -475);
PAINT MONO (2925 -475);
DISPLAY INVISIBLE (2925 -475);
FORCEADD RES..1
(100 2025);
FORCEPROP 1 LAST PACK_TYPE 0603
J 0
(175 1975);
DISPLAY 0.617021 (175 1975);
PAINT SKYBLUE (175 1975);
FORCEPROP 1 LAST PART_NUMBER G22178-002
J 0
(-50 1925);
DISPLAY 0.617021 (-50 1925);
PAINT BLUE (-50 1925);
FORCEPROP 1 LAST MATERIAL CHIP
J 0
(100 1875);
DISPLAY 0.617021 (100 1875);
PAINT SKYBLUE (100 1875);
FORCEPROP 1 LASTPIN (0 2025) $PN 1
J 0
(12 2037);
DISPLAY 0.787234 (12 2037);
PAINT ORANGE (12 2037);
FORCEPROP 1 LAST TOLERANCE 5.0%
J 0
(325 1975);
DISPLAY 0.617021 (325 1975);
PAINT SKYBLUE (325 1975);
FORCEPROP 1 LAST VALUE 0
J 2
(50 1975);
DISPLAY 0.617021 (50 1975);
PAINT SKYBLUE (50 1975);
FORCEPROP 1 LAST WATTAGE 1/10W
J 2
(75 1875);
DISPLAY 0.617021 (75 1875);
PAINT SKYBLUE (75 1875);
FORCEPROP 1 LAST LOCATION RT5
J 0
(200 2050);
DISPLAY 0.617021 (200 2050);
PAINT AQUA (200 2050);
FORCEPROP 1 LASTPIN (200 2025) $PN 2
J 0
(162 2037);
DISPLAY 0.787234 (162 2037);
PAINT ORANGE (162 2037);
FORCEPROP 2 LAST SEC_TYPE 0603
J 0
(50 2225);
DISPLAY 1.021277 (50 2225);
PAINT ORANGE (50 2225);
DISPLAY INVISIBLE (50 2225);
FORCEPROP 0 LAST SEC 1
J 0
(-150 2125);
DISPLAY 0.680851 (-150 2125);
PAINT MONO (-150 2125);
DISPLAY INVISIBLE (-150 2125);
FORCEPROP 0 LAST BOM_COST NT_GBE_BASE
J 0
(200 2250);
DISPLAY 1.021277 (200 2250);
PAINT ORANGE (200 2250);
DISPLAY INVISIBLE (200 2250);
FORCEPROP 0 LAST ROOM NIC_SPRV
J 0
(200 2150);
DISPLAY 1.021277 (200 2150);
PAINT ORANGE (200 2150);
DISPLAY INVISIBLE (200 2150);
FORCEPROP 1 LAST PATH I138
J 0
(50 2175);
DISPLAY 0.978723 (50 2175);
PAINT WHITE (50 2175);
DISPLAY INVISIBLE (50 2175);
FORCEPROP 2 LAST CDS_LIB mstr_discrete
J 0
(100 2025);
PAINT MONO (100 2025);
DISPLAY INVISIBLE (100 2025);
FORCEADD RES..1
(225 -250);
FORCEPROP 1 LAST LOCATION RT8
J 0
(50 -225);
DISPLAY 0.617021 (50 -225);
PAINT AQUA (50 -225);
FORCEPROP 1 LAST PART_NUMBER G22178-002
J 0
(125 -200);
DISPLAY 0.617021 (125 -200);
PAINT BLUE (125 -200);
FORCEPROP 1 LAST TOLERANCE 5.0%
J 0
(375 -400);
DISPLAY 0.617021 (375 -400);
PAINT SKYBLUE (375 -400);
FORCEPROP 1 LAST MATERIAL CHIP
J 0
(225 -400);
DISPLAY 0.617021 (225 -400);
PAINT SKYBLUE (225 -400);
FORCEPROP 1 LASTPIN (325 -250) $PN 2
J 0
(287 -238);
DISPLAY 0.787234 (287 -238);
PAINT ORANGE (287 -238);
FORCEPROP 1 LAST VALUE 0
J 2
(175 -300);
DISPLAY 0.617021 (175 -300);
PAINT SKYBLUE (175 -300);
FORCEPROP 1 LAST WATTAGE 1/10W
J 2
(175 -400);
DISPLAY 0.617021 (175 -400);
PAINT SKYBLUE (175 -400);
FORCEPROP 0 LAST BOM_SS NOPOP
J 0
(475 -325);
DISPLAY 0.638298 (475 -325);
PAINT BROWN (475 -325);
DISPLAY BOTH (475 -325);
FORCEPROP 1 LAST PACK_TYPE 0603
J 0
(300 -300);
DISPLAY 0.617021 (300 -300);
PAINT SKYBLUE (300 -300);
FORCEPROP 1 LASTPIN (125 -250) $PN 1
J 0
(137 -238);
DISPLAY 0.787234 (137 -238);
PAINT ORANGE (137 -238);
FORCEPROP 0 LAST BOM_COST NT_GBE_BASE
J 0
(325 -25);
DISPLAY 1.021277 (325 -25);
PAINT ORANGE (325 -25);
DISPLAY INVISIBLE (325 -25);
FORCEPROP 0 LAST ROOM NIC_SPRV
J 0
(325 -125);
DISPLAY 1.021277 (325 -125);
PAINT ORANGE (325 -125);
DISPLAY INVISIBLE (325 -125);
FORCEPROP 1 LAST PATH I139
J 0
(175 -100);
DISPLAY 0.978723 (175 -100);
PAINT WHITE (175 -100);
DISPLAY INVISIBLE (175 -100);
FORCEPROP 2 LAST CDS_LIB mstr_discrete
J 0
(225 -250);
PAINT MONO (225 -250);
DISPLAY INVISIBLE (225 -250);
FORCEPROP 2 LAST SEC_TYPE 0603
J 0
(175 -50);
DISPLAY 1.021277 (175 -50);
PAINT ORANGE (175 -50);
DISPLAY INVISIBLE (175 -50);
FORCEPROP 0 LAST SEC 1
J 0
(-25 -150);
DISPLAY 0.680851 (-25 -150);
PAINT MONO (-25 -150);
DISPLAY INVISIBLE (-25 -150);
FORCEADD SC1U10V2KX-4-GP..1
(-425 225);
FORCEPROP 2 LASTPIN (-425 150) $PN 2
R 1
J 2
(-435 140);
DISPLAY 0.808511 (-435 140);
PAINT ORANGE (-435 140);
FORCEPROP 2 LASTPIN (-425 300) $PN 1
R 1
J 0
(-435 310);
DISPLAY 0.808511 (-435 310);
PAINT ORANGE (-435 310);
FORCEPROP 2 LAST RATED 10V
J 0
(-300 150);
DISPLAY 0.638298 (-300 150);
PAINT GREEN (-300 150);
FORCEPROP 2 LAST PACK_SIZE 0402
J 0
(-300 100);
DISPLAY 0.638298 (-300 100);
PAINT GREEN (-300 100);
FORCEPROP 2 LAST ATTRIBUTE 1UF
J 0
(-300 250);
DISPLAY 0.638298 (-300 250);
PAINT GREEN (-300 250);
FORCEPROP 2 LAST TOLERANCE 10%
J 0
(-300 200);
DISPLAY 0.638298 (-300 200);
PAINT GREEN (-300 200);
FORCEPROP 0 LAST BOM_SS NOPOP
J 0
(-275 25);
DISPLAY 0.638298 (-275 25);
PAINT BROWN (-275 25);
DISPLAY BOTH (-275 25);
FORCEPROP 1 LAST VALUE SC1U10V2KX-4-GP
R 1
J 0
(-325 0);
DISPLAY 0.617021 (-325 0);
PAINT GREEN (-325 0);
FORCEPROP 1 LAST LOCATION C1A11
J 0
(-300 305);
DISPLAY 0.617021 (-300 305);
PAINT GREEN (-300 305);
FORCEPROP 1 LAST PACK_TYPE SMD-BCG6
J 0
(-425 225);
DISPLAY 0.617021 (-425 225);
PAINT GREEN (-425 225);
DISPLAY INVISIBLE (-425 225);
FORCEPROP 2 LAST SEC 1
J 0
(-400 300);
DISPLAY 0.680851 (-400 300);
PAINT MONO (-400 300);
DISPLAY INVISIBLE (-400 300);
FORCEPROP 2 LAST SEC_TYPE SMD-BCG6
J 0
(-400 300);
DISPLAY 1.021277 (-400 300);
PAINT ORANGE (-400 300);
DISPLAY INVISIBLE (-400 300);
FORCEPROP 1 LAST PART_NUMBER 78.10523.8FL
J 0
(-425 225);
DISPLAY 0.617021 (-425 225);
PAINT GREEN (-425 225);
DISPLAY INVISIBLE (-425 225);
FORCEPROP 2 LAST CDS_LIB w_hdl
J 0
(-425 225);
PAINT MONO (-425 225);
DISPLAY INVISIBLE (-425 225);
FORCEPROP 1 LAST PATH I147
J 0
(-425 225);
DISPLAY 0.617021 (-425 225);
PAINT GREEN (-425 225);
DISPLAY INVISIBLE (-425 225);
FORCEPROP 1 LAST CDS_LMAN_SYM_OUTLINE -50,25,50,-25
J 0
(-425 225);
DISPLAY 0.468085 (-425 225);
PAINT GREEN (-425 225);
DISPLAY INVISIBLE (-425 225);
FORCEADD SC1U10V2KX-4-GP..1
(-475 2475);
FORCEPROP 2 LAST ATTRIBUTE 1UF
J 0
(-325 2500);
DISPLAY 0.638298 (-325 2500);
PAINT GREEN (-325 2500);
FORCEPROP 1 LAST VALUE SC1U10V2KX-4-GP
R 1
J 0
(-375 2225);
DISPLAY 0.617021 (-375 2225);
PAINT GREEN (-375 2225);
FORCEPROP 2 LASTPIN (-475 2400) $PN 2
R 1
J 2
(-485 2390);
DISPLAY 0.808511 (-485 2390);
PAINT ORANGE (-485 2390);
FORCEPROP 2 LAST PACK_SIZE 0402
J 0
(-325 2350);
DISPLAY 0.638298 (-325 2350);
PAINT GREEN (-325 2350);
FORCEPROP 2 LAST RATED 10V
J 0
(-325 2400);
DISPLAY 0.638298 (-325 2400);
PAINT GREEN (-325 2400);
FORCEPROP 2 LAST TOLERANCE 10%
J 0
(-325 2450);
DISPLAY 0.638298 (-325 2450);
PAINT GREEN (-325 2450);
FORCEPROP 1 LAST LOCATION C1A2
J 0
(-325 2555);
DISPLAY 0.617021 (-325 2555);
PAINT GREEN (-325 2555);
FORCEPROP 2 LASTPIN (-475 2550) $PN 1
R 1
J 0
(-485 2560);
DISPLAY 0.808511 (-485 2560);
PAINT ORANGE (-485 2560);
FORCEPROP 1 LAST CDS_LMAN_SYM_OUTLINE -50,25,50,-25
J 0
(-475 2475);
DISPLAY 0.468085 (-475 2475);
PAINT GREEN (-475 2475);
DISPLAY INVISIBLE (-475 2475);
FORCEPROP 1 LAST PATH I148
J 0
(-475 2475);
DISPLAY 0.617021 (-475 2475);
PAINT GREEN (-475 2475);
DISPLAY INVISIBLE (-475 2475);
FORCEPROP 2 LAST CDS_LIB w_hdl
J 0
(-475 2475);
PAINT MONO (-475 2475);
DISPLAY INVISIBLE (-475 2475);
FORCEPROP 1 LAST PART_NUMBER 78.10523.8FL
J 0
(-475 2475);
DISPLAY 0.617021 (-475 2475);
PAINT GREEN (-475 2475);
DISPLAY INVISIBLE (-475 2475);
FORCEPROP 2 LAST SEC_TYPE SMD-BCG6
J 0
(-475 2525);
DISPLAY 1.021277 (-475 2525);
PAINT ORANGE (-475 2525);
DISPLAY INVISIBLE (-475 2525);
FORCEPROP 2 LAST SEC 1
J 0
(-475 2525);
DISPLAY 0.680851 (-475 2525);
PAINT MONO (-475 2525);
DISPLAY INVISIBLE (-475 2525);
FORCEPROP 1 LAST PACK_TYPE SMD-BCG6
J 0
(-475 2475);
DISPLAY 0.617021 (-475 2475);
PAINT GREEN (-475 2475);
DISPLAY INVISIBLE (-475 2475);
FORCEADD 1R3F-GP..1
(2825 1325);
FORCEPROP 2 LAST RATED 1/10W
J 0
(2875 1250);
DISPLAY 0.638298 (2875 1250);
PAINT GREEN (2875 1250);
FORCEPROP 2 LAST TOLERANCE 1%
J 0
(2875 1300);
DISPLAY 0.638298 (2875 1300);
PAINT GREEN (2875 1300);
FORCEPROP 2 LAST PACK_SIZE 0603
J 0
(2875 1200);
DISPLAY 0.638298 (2875 1200);
PAINT GREEN (2875 1200);
FORCEPROP 1 LAST LOCATION RT6
J 0
(2875 1450);
DISPLAY 0.617021 (2875 1450);
PAINT GREEN (2875 1450);
FORCEPROP 2 LAST ATTRIBUTE 1 OHM
J 0
(2875 1350);
DISPLAY 0.638298 (2875 1350);
PAINT GREEN (2875 1350);
FORCEPROP 2 LASTPIN (2825 1200) $PN 2
R 1
J 2
(2815 1190);
DISPLAY 0.808511 (2815 1190);
PAINT ORANGE (2815 1190);
FORCEPROP 2 LASTPIN (2825 1450) $PN 1
R 1
J 0
(2815 1460);
DISPLAY 0.808511 (2815 1460);
PAINT ORANGE (2815 1460);
FORCEPROP 0 LAST POP NOPOP
J 0
(2875 1150);
DISPLAY 0.638298 (2875 1150);
PAINT RED (2875 1150);
FORCEPROP 1 LAST VALUE 1R3F-GP
J 0
(2875 1400);
DISPLAY 0.617021 (2875 1400);
PAINT GREEN (2875 1400);
FORCEPROP 1 LAST PACK_TYPE RCL_GP
J 0
(2825 1325);
DISPLAY 0.617021 (2825 1325);
PAINT GREEN (2825 1325);
DISPLAY INVISIBLE (2825 1325);
FORCEPROP 2 LAST SEC 1
J 0
(2875 1425);
DISPLAY 0.680851 (2875 1425);
PAINT MONO (2875 1425);
DISPLAY INVISIBLE (2875 1425);
FORCEPROP 2 LAST SEC_TYPE RCL_GP
J 0
(2875 1425);
DISPLAY 1.021277 (2875 1425);
PAINT ORANGE (2875 1425);
DISPLAY INVISIBLE (2875 1425);
FORCEPROP 1 LAST PART_NUMBER 64.1R005.55L
J 0
(2825 1325);
DISPLAY 0.617021 (2825 1325);
PAINT GREEN (2825 1325);
DISPLAY INVISIBLE (2825 1325);
FORCEPROP 2 LAST CDS_LIB w_hdl
J 0
(2825 1325);
DISPLAY INVISIBLE (2825 1325);
FORCEPROP 1 LAST CDS_LMAN_SYM_OUTLINE -50,75,50,-75
J 0
(2825 1325);
DISPLAY 0.468085 (2825 1325);
PAINT GREEN (2825 1325);
DISPLAY INVISIBLE (2825 1325);
FORCEPROP 1 LAST PATH I149
J 0
(2825 1325);
DISPLAY 0.617021 (2825 1325);
PAINT GREEN (2825 1325);
DISPLAY INVISIBLE (2825 1325);
FORCEADD 1R3F-GP..1
(2925 -800);
FORCEPROP 2 LASTPIN (2925 -675) $PN 1
R 1
J 0
(2915 -665);
DISPLAY 0.808511 (2915 -665);
PAINT ORANGE (2915 -665);
FORCEPROP 1 LAST LOCATION RT7
J 0
(2975 -675);
DISPLAY 0.617021 (2975 -675);
PAINT GREEN (2975 -675);
FORCEPROP 2 LAST PACK_SIZE 0603
J 0
(2975 -925);
DISPLAY 0.638298 (2975 -925);
PAINT GREEN (2975 -925);
FORCEPROP 2 LAST TOLERANCE 1%
J 0
(2975 -825);
DISPLAY 0.638298 (2975 -825);
PAINT GREEN (2975 -825);
FORCEPROP 2 LASTPIN (2925 -925) $PN 2
R 1
J 2
(2915 -935);
DISPLAY 0.808511 (2915 -935);
PAINT ORANGE (2915 -935);
FORCEPROP 2 LAST ATTRIBUTE 1 OHM
J 0
(2975 -775);
DISPLAY 0.638298 (2975 -775);
PAINT GREEN (2975 -775);
FORCEPROP 0 LAST POP NOPOP
J 0
(2975 -975);
DISPLAY 0.638298 (2975 -975);
PAINT RED (2975 -975);
FORCEPROP 1 LAST VALUE 1R3F-GP
J 0
(2975 -725);
DISPLAY 0.617021 (2975 -725);
PAINT GREEN (2975 -725);
FORCEPROP 2 LAST RATED 1/10W
J 0
(2975 -875);
DISPLAY 0.638298 (2975 -875);
PAINT GREEN (2975 -875);
FORCEPROP 0 LAST BOM_SS NOPOP
J 0
(3150 -775);
DISPLAY 0.638298 (3150 -775);
PAINT BROWN (3150 -775);
DISPLAY BOTH (3150 -775);
FORCEPROP 1 LAST CDS_LMAN_SYM_OUTLINE -50,75,50,-75
J 0
(2925 -800);
DISPLAY 0.468085 (2925 -800);
PAINT GREEN (2925 -800);
DISPLAY INVISIBLE (2925 -800);
FORCEPROP 2 LAST CDS_LIB w_hdl
J 0
(2925 -800);
DISPLAY INVISIBLE (2925 -800);
FORCEPROP 1 LAST PART_NUMBER 64.1R005.55L
J 0
(2925 -800);
DISPLAY 0.617021 (2925 -800);
PAINT GREEN (2925 -800);
DISPLAY INVISIBLE (2925 -800);
FORCEPROP 2 LAST SEC_TYPE RCL_GP
J 0
(2975 -700);
DISPLAY 1.021277 (2975 -700);
PAINT ORANGE (2975 -700);
DISPLAY INVISIBLE (2975 -700);
FORCEPROP 2 LAST SEC 1
J 0
(2975 -700);
DISPLAY 0.680851 (2975 -700);
PAINT MONO (2975 -700);
DISPLAY INVISIBLE (2975 -700);
FORCEPROP 1 LAST PACK_TYPE RCL_GP
J 0
(2925 -800);
DISPLAY 0.617021 (2925 -800);
PAINT GREEN (2925 -800);
DISPLAY INVISIBLE (2925 -800);
FORCEPROP 1 LAST PATH I150
J 0
(2925 -800);
DISPLAY 0.617021 (2925 -800);
PAINT GREEN (2925 -800);
DISPLAY INVISIBLE (2925 -800);
FORCEADD IND-120NH-30-GP..1
R 1
(3775 1950);
FORCEPROP 2 LASTPIN (3925 1925) $PN 2
J 0
(3935 1935);
DISPLAY 0.808511 (3935 1935);
PAINT ORANGE (3935 1935);
FORCEPROP 2 LASTPIN (3625 1925) $PN 1
J 2
(3615 1935);
DISPLAY 0.808511 (3615 1935);
PAINT ORANGE (3615 1935);
FORCEPROP 0 LAST NEW_TYPE IRMS=66A@DELTA_T<40C
J 0
(3575 1550);
DISPLAY 0.638298 (3575 1550);
PAINT BROWN (3575 1550);
FORCEPROP 0 LAST BOM_DS 068.9002N.1021
J 0
(3575 1700);
DISPLAY 0.638298 (3575 1700);
PAINT BROWN (3575 1700);
DISPLAY BOTH (3575 1700);
FORCEPROP 0 LAST DS_VALUE 90NH
J 0
(3575 1650);
DISPLAY 0.638298 (3575 1650);
PAINT BROWN (3575 1650);
DISPLAY BOTH (3575 1650);
FORCEPROP 0 LAST NEW_RATED DS_ISAT=134A@25C
J 0
(3575 1600);
DISPLAY 0.638298 (3575 1600);
PAINT BROWN (3575 1600);
FORCEPROP 1 LAST LOCATION L1A2
J 0
(3625 2000);
DISPLAY 0.617021 (3625 2000);
PAINT GREEN (3625 2000);
FORCEPROP 0 LAST BOM_SS 068.1202N.M001
J 0
(3575 1850);
DISPLAY 0.638298 (3575 1850);
PAINT BROWN (3575 1850);
DISPLAY BOTH (3575 1850);
FORCEPROP 0 LAST SS_ISAT 94A@25C
J 0
(3575 1750);
DISPLAY 0.638298 (3575 1750);
PAINT BROWN (3575 1750);
DISPLAY BOTH (3575 1750);
FORCEPROP 0 LAST SS_VALUE 120NH
J 0
(3575 1800);
DISPLAY 0.638298 (3575 1800);
PAINT BROWN (3575 1800);
DISPLAY BOTH (3575 1800);
FORCEPROP 0 LAST NEW_PACK_SIZE DCR=0.17MOHM
J 0
(3575 1500);
DISPLAY 0.638298 (3575 1500);
PAINT BROWN (3575 1500);
FORCEPROP 1 LAST PATH I152
R 1
J 0
(3775 1950);
DISPLAY 0.617021 (3775 1950);
PAINT GREEN (3775 1950);
DISPLAY INVISIBLE (3775 1950);
FORCEPROP 0 LAST TYPE IRMS=66A@DELTA_T<40C
J 0
(3625 1700);
DISPLAY 0.638298 (3625 1700);
PAINT GREEN (3625 1700);
DISPLAY INVISIBLE (3625 1700);
FORCEPROP 0 LAST PACK_SIZE DCR=0.17MOHM
J 0
(3625 1650);
DISPLAY 0.638298 (3625 1650);
PAINT GREEN (3625 1650);
DISPLAY INVISIBLE (3625 1650);
FORCEPROP 0 LAST RATED ISAT=94A@25C
J 0
(3625 1750);
DISPLAY 0.638298 (3625 1750);
PAINT GREEN (3625 1750);
DISPLAY INVISIBLE (3625 1750);
FORCEPROP 0 LAST ATTRIBUTE 120NH
J 0
(3625 1800);
DISPLAY 0.638298 (3625 1800);
PAINT GREEN (3625 1800);
DISPLAY INVISIBLE (3625 1800);
FORCEPROP 1 LAST VALUE IND-120NH-30-GP
J 0
(3625 1850);
DISPLAY 0.617021 (3625 1850);
PAINT GREEN (3625 1850);
DISPLAY INVISIBLE (3625 1850);
FORCEPROP 1 LAST PACK_TYPE DISCRET-GB2
R 1
J 0
(3775 1950);
DISPLAY 0.617021 (3775 1950);
PAINT GREEN (3775 1950);
DISPLAY INVISIBLE (3775 1950);
FORCEPROP 2 LAST SEC 1
J 0
(3650 2025);
DISPLAY 0.680851 (3650 2025);
PAINT MONO (3650 2025);
DISPLAY INVISIBLE (3650 2025);
FORCEPROP 2 LAST SEC_TYPE DISCRET-GB2
J 0
(3650 2025);
DISPLAY 1.021277 (3650 2025);
PAINT ORANGE (3650 2025);
DISPLAY INVISIBLE (3650 2025);
FORCEPROP 1 LAST CDS_LMAN_SYM_OUTLINE -75,100,75,-100
R 1
J 0
(3775 1950);
DISPLAY 0.468085 (3775 1950);
PAINT GREEN (3775 1950);
DISPLAY INVISIBLE (3775 1950);
FORCEPROP 2 LAST CDS_LIB w_hdl
R 1
J 0
(3775 1950);
PAINT MONO (3775 1950);
DISPLAY INVISIBLE (3775 1950);
FORCEPROP 1 LAST PART_NUMBER 068.1202N.M001
R 1
J 0
(3775 1950);
DISPLAY 0.617021 (3775 1950);
PAINT GREEN (3775 1950);
DISPLAY INVISIBLE (3775 1950);
FORCEADD IND-120NH-30-GP..1
R 1
(3775 -300);
FORCEPROP 0 LAST NEW_PACK_SIZE DCR=0.17MOHM
J 0
(3575 -650);
DISPLAY 0.638298 (3575 -650);
PAINT BROWN (3575 -650);
FORCEPROP 0 LAST DS_VALUE 90NH
J 0
(3575 -500);
DISPLAY 0.638298 (3575 -500);
PAINT BROWN (3575 -500);
DISPLAY BOTH (3575 -500);
FORCEPROP 1 LAST LOCATION L1A1
J 0
(3625 -250);
DISPLAY 0.617021 (3625 -250);
PAINT GREEN (3625 -250);
FORCEPROP 2 LASTPIN (3625 -325) $PN 1
J 2
(3615 -315);
DISPLAY 0.808511 (3615 -315);
PAINT ORANGE (3615 -315);
FORCEPROP 2 LASTPIN (3925 -325) $PN 2
J 0
(3935 -315);
DISPLAY 0.808511 (3935 -315);
PAINT ORANGE (3935 -315);
FORCEPROP 0 LAST BOM_DS 068.9002N.1021
J 0
(3575 -450);
DISPLAY 0.638298 (3575 -450);
PAINT BROWN (3575 -450);
DISPLAY BOTH (3575 -450);
FORCEPROP 0 LAST BOM_SS NOPOP
J 0
(3575 -400);
DISPLAY 0.638298 (3575 -400);
PAINT BROWN (3575 -400);
DISPLAY BOTH (3575 -400);
FORCEPROP 0 LAST NEW_TYPE IRMS=66A@DELTA_T<40C
J 0
(3575 -600);
DISPLAY 0.638298 (3575 -600);
PAINT BROWN (3575 -600);
FORCEPROP 0 LAST NEW_RATED DS_ISAT=134A@25C
J 0
(3575 -550);
DISPLAY 0.638298 (3575 -550);
PAINT BROWN (3575 -550);
FORCEPROP 1 LAST PATH I153
R 1
J 0
(3775 -300);
DISPLAY 0.617021 (3775 -300);
PAINT GREEN (3775 -300);
DISPLAY INVISIBLE (3775 -300);
FORCEPROP 1 LAST PART_NUMBER 068.1202N.M001
R 1
J 0
(3775 -300);
DISPLAY 0.617021 (3775 -300);
PAINT GREEN (3775 -300);
DISPLAY INVISIBLE (3775 -300);
FORCEPROP 2 LAST CDS_LIB w_hdl
R 1
J 0
(3775 -300);
PAINT MONO (3775 -300);
DISPLAY INVISIBLE (3775 -300);
FORCEPROP 1 LAST CDS_LMAN_SYM_OUTLINE -75,100,75,-100
R 1
J 0
(3775 -300);
DISPLAY 0.468085 (3775 -300);
PAINT GREEN (3775 -300);
DISPLAY INVISIBLE (3775 -300);
FORCEPROP 2 LAST SEC_TYPE DISCRET-GB2
J 0
(3650 -225);
DISPLAY 1.021277 (3650 -225);
PAINT ORANGE (3650 -225);
DISPLAY INVISIBLE (3650 -225);
FORCEPROP 2 LAST SEC 1
J 0
(3650 -225);
DISPLAY 0.680851 (3650 -225);
PAINT MONO (3650 -225);
DISPLAY INVISIBLE (3650 -225);
FORCEPROP 1 LAST PACK_TYPE DISCRET-GB2
R 1
J 0
(3775 -300);
DISPLAY 0.617021 (3775 -300);
PAINT GREEN (3775 -300);
DISPLAY INVISIBLE (3775 -300);
FORCEPROP 1 LAST VALUE IND-120NH-30-GP
J 0
(3625 -400);
DISPLAY 0.617021 (3625 -400);
PAINT GREEN (3625 -400);
DISPLAY INVISIBLE (3625 -400);
FORCEPROP 0 LAST ATTRIBUTE 120NH
J 0
(3625 -450);
DISPLAY 0.638298 (3625 -450);
PAINT GREEN (3625 -450);
DISPLAY INVISIBLE (3625 -450);
FORCEPROP 0 LAST RATED ISAT=94A@25C
J 0
(3625 -500);
DISPLAY 0.638298 (3625 -500);
PAINT GREEN (3625 -500);
DISPLAY INVISIBLE (3625 -500);
FORCEPROP 0 LAST PACK_SIZE DCR=0.17MOHM
J 0
(3625 -600);
DISPLAY 0.638298 (3625 -600);
PAINT GREEN (3625 -600);
DISPLAY INVISIBLE (3625 -600);
FORCEPROP 0 LAST TYPE IRMS=66A@DELTA_T<40C
J 0
(3625 -550);
DISPLAY 0.638298 (3625 -550);
PAINT GREEN (3625 -550);
DISPLAY INVISIBLE (3625 -550);
FORCEADD RES..1
(-750 3100);
FORCEPROP 1 LAST WATTAGE 1/16W
J 2
(-400 3150);
DISPLAY 0.510638 (-400 3150);
PAINT SKYBLUE (-400 3150);
FORCEPROP 1 LASTPIN (-650 3100) $PN 2
J 0
(-688 3112);
DISPLAY 0.617021 (-688 3112);
PAINT WHITE (-688 3112);
FORCEPROP 1 LAST LOCATION R9L9
J 0
(-850 3150);
DISPLAY 0.617021 (-850 3150);
PAINT AQUA (-850 3150);
FORCEPROP 1 LAST PART_NUMBER G21497-005
J 0
(-875 3050);
DISPLAY 0.617021 (-875 3050);
PAINT BLUE (-875 3050);
FORCEPROP 1 LAST MATERIAL CHIP
J 0
(-525 3000);
DISPLAY 0.510638 (-525 3000);
PAINT SKYBLUE (-525 3000);
FORCEPROP 1 LAST VALUE 0.0
J 2
(-850 3000);
DISPLAY 0.617021 (-850 3000);
PAINT SKYBLUE (-850 3000);
FORCEPROP 1 LAST PACK_TYPE 0402
J 0
(-675 3000);
DISPLAY 0.617021 (-675 3000);
PAINT SKYBLUE (-675 3000);
FORCEPROP 1 LAST TOLERANCE 5%
J 0
(-800 3000);
DISPLAY 0.617021 (-800 3000);
PAINT SKYBLUE (-800 3000);
FORCEPROP 1 LASTPIN (-850 3100) $PN 1
J 0
(-838 3112);
DISPLAY 0.617021 (-838 3112);
PAINT WHITE (-838 3112);
FORCEPROP 2 LAST CDS_LOCATION R9L9
J 0
(-1225 3100);
DISPLAY 0.617021 (-1225 3100);
PAINT AQUA (-1225 3100);
DISPLAY INVISIBLE (-1225 3100);
FORCEPROP 1 LAST PATH I154
J 0
(-800 3250);
DISPLAY 0.978723 (-800 3250);
PAINT WHITE (-800 3250);
DISPLAY INVISIBLE (-800 3250);
FORCEPROP 2 LAST BOM_COST PROC_SIDEBAND
J 0
(-750 3100);
PAINT MONO (-750 3100);
DISPLAY INVISIBLE (-750 3100);
FORCEPROP 2 LAST CDS_LIB mstr_discrete
J 0
(-750 3100);
DISPLAY 1.340426 (-750 3100);
PAINT ORANGE (-750 3100);
DISPLAY INVISIBLE (-750 3100);
FORCEPROP 2 LAST SEC_TYPE 0402
J 0
(-800 3325);
DISPLAY 1.021277 (-800 3325);
PAINT ORANGE (-800 3325);
DISPLAY INVISIBLE (-800 3325);
FORCEPROP 2 LAST SEC 1
J 0
(-800 3325);
DISPLAY 0.680851 (-800 3325);
PAINT MONO (-800 3325);
DISPLAY INVISIBLE (-800 3325);
FORCEPROP 2 LAST ROOM CPU0
J 0
(-800 3250);
PAINT PEACH (-800 3250);
DISPLAY INVISIBLE (-800 3250);
FORCEPROP 0 LAST CDS_SEC 1
J 0
(-450 3150);
PAINT MONO (-450 3150);
DISPLAY INVISIBLE (-450 3150);
FORCEADD RES..1
(-675 800);
FORCEPROP 0 LAST BOM_SS NOPOP
J 0
(-325 850);
DISPLAY 0.638298 (-325 850);
PAINT BROWN (-325 850);
DISPLAY BOTH (-325 850);
FORCEPROP 1 LAST WATTAGE 1/16W
J 2
(-350 850);
DISPLAY 0.510638 (-350 850);
PAINT SKYBLUE (-350 850);
FORCEPROP 1 LAST PART_NUMBER G21497-005
J 0
(-800 750);
DISPLAY 0.617021 (-800 750);
PAINT BLUE (-800 750);
FORCEPROP 1 LAST VALUE 0.0
J 2
(-775 700);
DISPLAY 0.617021 (-775 700);
PAINT SKYBLUE (-775 700);
FORCEPROP 1 LAST LOCATION R9L4
J 0
(-775 850);
DISPLAY 0.617021 (-775 850);
PAINT AQUA (-775 850);
FORCEPROP 1 LAST MATERIAL CHIP
J 0
(-450 700);
DISPLAY 0.510638 (-450 700);
PAINT SKYBLUE (-450 700);
FORCEPROP 1 LASTPIN (-575 800) $PN 2
J 0
(-613 812);
DISPLAY 0.617021 (-613 812);
PAINT WHITE (-613 812);
FORCEPROP 1 LAST TOLERANCE 5%
J 0
(-725 700);
DISPLAY 0.617021 (-725 700);
PAINT SKYBLUE (-725 700);
FORCEPROP 1 LASTPIN (-775 800) $PN 1
J 0
(-763 812);
DISPLAY 0.617021 (-763 812);
PAINT WHITE (-763 812);
FORCEPROP 1 LAST PACK_TYPE 0402
J 0
(-600 700);
DISPLAY 0.617021 (-600 700);
PAINT SKYBLUE (-600 700);
FORCEPROP 2 LAST CDS_LOCATION R9L4
J 0
(-1150 800);
DISPLAY 0.617021 (-1150 800);
PAINT AQUA (-1150 800);
DISPLAY INVISIBLE (-1150 800);
FORCEPROP 1 LAST PATH I155
J 0
(-725 950);
DISPLAY 0.978723 (-725 950);
PAINT WHITE (-725 950);
DISPLAY INVISIBLE (-725 950);
FORCEPROP 2 LAST BOM_COST PROC_SIDEBAND
J 0
(-675 800);
PAINT MONO (-675 800);
DISPLAY INVISIBLE (-675 800);
FORCEPROP 2 LAST CDS_LIB mstr_discrete
J 0
(-675 800);
DISPLAY 1.340426 (-675 800);
PAINT ORANGE (-675 800);
DISPLAY INVISIBLE (-675 800);
FORCEPROP 2 LAST SEC_TYPE 0402
J 0
(-725 1025);
DISPLAY 1.021277 (-725 1025);
PAINT ORANGE (-725 1025);
DISPLAY INVISIBLE (-725 1025);
FORCEPROP 2 LAST SEC 1
J 0
(-725 1025);
DISPLAY 0.680851 (-725 1025);
PAINT MONO (-725 1025);
DISPLAY INVISIBLE (-725 1025);
FORCEPROP 2 LAST ROOM CPU0
J 0
(-725 950);
PAINT PEACH (-725 950);
DISPLAY INVISIBLE (-725 950);
FORCEPROP 0 LAST CDS_SEC 1
J 0
(-375 850);
PAINT MONO (-375 850);
DISPLAY INVISIBLE (-375 850);
FORCEADD GND..1
(2675 1475);
FORCEPROP 3 LASTPIN (2675 1525) SIG_NAME GND\g
J 0
(2685 1535);
DISPLAY 0.659574 (2685 1535);
PAINT MONO (2685 1535);
DISPLAY INVISIBLE (2685 1535);
FORCEPROP 1 LAST HDL_POWER GND
J 0
(2675 1625);
DISPLAY 1.723404 (2675 1625);
PAINT GREEN (2675 1625);
DISPLAY INVISIBLE (2675 1625);
FORCEPROP 1 LAST BODY_TYPE PLUMBING
J 0
(2630 1432);
DISPLAY 0.340426 (2630 1432);
PAINT GREEN (2630 1432);
DISPLAY INVISIBLE (2630 1432);
FORCEPROP 2 LAST BOM_COST VDDQ_KLM_PWR_VR
J 0
(2300 1550);
DISPLAY 1.446809 (2300 1550);
PAINT MONO (2300 1550);
DISPLAY INVISIBLE (2300 1550);
FORCEPROP 2 LAST ROOM VDDQ_KLM_PWR_VR
J 0
(2125 1550);
DISPLAY 1.936170 (2125 1550);
PAINT ORANGE (2125 1550);
DISPLAY INVISIBLE (2125 1550);
FORCEPROP 1 LAST VOLTAGE 0
J 0
(2675 1475);
PAINT SKYBLUE (2675 1475);
DISPLAY INVISIBLE (2675 1475);
FORCEPROP 2 LAST CDS_LIB mstr_symbols
J 0
(2675 1475);
DISPLAY 1.936170 (2675 1475);
PAINT ORANGE (2675 1475);
DISPLAY INVISIBLE (2675 1475);
FORCEPROP 1 LAST SIZE 1B
J 0
(2750 1425);
DISPLAY 1.723404 (2750 1425);
PAINT GREEN (2750 1425);
DISPLAY INVISIBLE (2750 1425);
FORCEPROP 1 LAST PATH I19
J 0
(2750 1475);
DISPLAY 0.893617 (2750 1475);
PAINT AQUA (2750 1475);
DISPLAY INVISIBLE (2750 1475);
FORCEADD OFFPAGE..2
(3550 2775);
FORCEPROP 2 LAST $XR0 226 
J 0
(3739 2775);
DISPLAY 0.638298 (3739 2775);
PAINT MONO (3739 2775);
FORCEPROP 1 LAST COMMENT_BODY TRUE
J 0
(3505 2680);
DISPLAY 1.723404 (3505 2680);
PAINT GREEN (3505 2680);
DISPLAY INVISIBLE (3505 2680);
FORCEPROP 1 LAST OFFPAGE TRUE
J 0
(3875 2650);
DISPLAY 1.723404 (3875 2650);
PAINT GREEN (3875 2650);
DISPLAY INVISIBLE (3875 2650);
FORCEPROP 2 LAST ROOM VDDQ_KLM_PWR_VR
J 0
(3150 2850);
DISPLAY 1.936170 (3150 2850);
PAINT ORANGE (3150 2850);
DISPLAY INVISIBLE (3150 2850);
FORCEPROP 2 LAST CDS_LIB mstr_standard
J 0
(3550 2775);
DISPLAY 1.936170 (3550 2775);
PAINT ORANGE (3550 2775);
DISPLAY INVISIBLE (3550 2775);
FORCEPROP 2 LAST PATH I3
J 0
(3740 2825);
DISPLAY 1.021277 (3740 2825);
PAINT ORANGE (3740 2825);
DISPLAY INVISIBLE (3740 2825);
FORCEPROP 2 LAST BOM_COST VDDQ_KLM_PWR_VR
J 0
(3750 2825);
DISPLAY 1.446809 (3750 2825);
PAINT MONO (3750 2825);
DISPLAY INVISIBLE (3750 2825);
FORCEADD OFFPAGE..1
(-1475 2125);
FORCEPROP 2 LASTPIN (-1425 2125) SIG_NAME VR_PVDDQ_KLM_PWM1
J 0
(-1410 2135);
DISPLAY 0.617021 (-1410 2135);
PAINT ORANGE (-1410 2135);
FORCEPROP 2 LAST $XR0 226 
J 0
(-1727 2125);
DISPLAY 0.638298 (-1727 2125);
PAINT MONO (-1727 2125);
FORCEPROP 1 LAST COMMENT_BODY TRUE
J 0
(-1350 2025);
DISPLAY 1.680851 (-1350 2025);
PAINT GREEN (-1350 2025);
DISPLAY INVISIBLE (-1350 2025);
FORCEPROP 1 LAST OFFPAGE TRUE
J 0
(-1150 2000);
DISPLAY 1.680851 (-1150 2000);
PAINT GREEN (-1150 2000);
DISPLAY INVISIBLE (-1150 2000);
FORCEPROP 2 LAST BOM_COST VDDQ_KLM_PWR_VR
J 0
(-1725 2175);
DISPLAY 1.446809 (-1725 2175);
PAINT MONO (-1725 2175);
DISPLAY INVISIBLE (-1725 2175);
FORCEPROP 2 LAST ROOM VDDQ_KLM_PWR_VR
J 0
(-1875 2200);
DISPLAY 1.936170 (-1875 2200);
PAINT ORANGE (-1875 2200);
DISPLAY INVISIBLE (-1875 2200);
FORCEPROP 2 LAST PATH I33
J 0
(-1755 2175);
DISPLAY 1.021277 (-1755 2175);
PAINT ORANGE (-1755 2175);
DISPLAY INVISIBLE (-1755 2175);
FORCEPROP 2 LAST CDS_LIB mstr_standard
J 0
(-1475 2125);
DISPLAY 1.936170 (-1475 2125);
PAINT ORANGE (-1475 2125);
DISPLAY INVISIBLE (-1475 2125);
FORCEADD GND..1
(-2250 2125);
FORCEPROP 3 LASTPIN (-2250 2175) SIG_NAME GND\g
J 0
(-2240 2185);
DISPLAY 0.659574 (-2240 2185);
PAINT MONO (-2240 2185);
DISPLAY INVISIBLE (-2240 2185);
FORCEPROP 1 LAST HDL_POWER GND
J 0
(-2250 2275);
DISPLAY 1.723404 (-2250 2275);
PAINT GREEN (-2250 2275);
DISPLAY INVISIBLE (-2250 2275);
FORCEPROP 1 LAST BODY_TYPE PLUMBING
J 0
(-2295 2082);
DISPLAY 0.340426 (-2295 2082);
PAINT GREEN (-2295 2082);
DISPLAY INVISIBLE (-2295 2082);
FORCEPROP 1 LAST PATH I35
J 0
(-2175 2125);
DISPLAY 0.893617 (-2175 2125);
PAINT AQUA (-2175 2125);
DISPLAY INVISIBLE (-2175 2125);
FORCEPROP 1 LAST SIZE 1B
J 0
(-2175 2075);
DISPLAY 1.723404 (-2175 2075);
PAINT GREEN (-2175 2075);
DISPLAY INVISIBLE (-2175 2075);
FORCEPROP 1 LAST VOLTAGE 0
J 0
(-2250 2125);
PAINT SKYBLUE (-2250 2125);
DISPLAY INVISIBLE (-2250 2125);
FORCEPROP 2 LAST CDS_LIB mstr_symbols
J 0
(-2250 2125);
DISPLAY 1.936170 (-2250 2125);
PAINT ORANGE (-2250 2125);
DISPLAY INVISIBLE (-2250 2125);
FORCEPROP 2 LAST ROOM VDDQ_KLM_PWR_VR
J 0
(-2800 2200);
DISPLAY 1.936170 (-2800 2200);
PAINT ORANGE (-2800 2200);
DISPLAY INVISIBLE (-2800 2200);
FORCEPROP 2 LAST BOM_COST VDDQ_KLM_PWR_VR
J 0
(-2625 2200);
DISPLAY 1.446809 (-2625 2200);
PAINT MONO (-2625 2200);
DISPLAY INVISIBLE (-2625 2200);
FORCEADD OFFPAGE..2
(3525 3100);
FORCEPROP 2 LAST $XR0 226 
J 0
(3714 3100);
DISPLAY 0.638298 (3714 3100);
PAINT MONO (3714 3100);
FORCEPROP 1 LAST COMMENT_BODY TRUE
J 0
(3480 3005);
DISPLAY 1.723404 (3480 3005);
PAINT GREEN (3480 3005);
DISPLAY INVISIBLE (3480 3005);
FORCEPROP 1 LAST OFFPAGE TRUE
J 0
(3850 2975);
DISPLAY 1.723404 (3850 2975);
PAINT GREEN (3850 2975);
DISPLAY INVISIBLE (3850 2975);
FORCEPROP 2 LAST ROOM VDDQ_KLM_PWR_VR
J 0
(3125 3175);
DISPLAY 1.936170 (3125 3175);
PAINT ORANGE (3125 3175);
DISPLAY INVISIBLE (3125 3175);
FORCEPROP 2 LAST CDS_LIB mstr_standard
J 2
(3525 3100);
DISPLAY 1.936170 (3525 3100);
PAINT ORANGE (3525 3100);
DISPLAY INVISIBLE (3525 3100);
FORCEPROP 2 LAST PATH I4
J 0
(3715 3150);
DISPLAY 1.021277 (3715 3150);
PAINT ORANGE (3715 3150);
DISPLAY INVISIBLE (3715 3150);
FORCEPROP 2 LAST BOM_COST VDDQ_KLM_PWR_VR
J 0
(3725 3150);
DISPLAY 1.446809 (3725 3150);
PAINT MONO (3725 3150);
DISPLAY INVISIBLE (3725 3150);
FORCEADD CAP..1
R 2
(-825 1925);
FORCEPROP 1 LAST PART_NUMBER A36096-104
J 2
(-875 1775);
DISPLAY 0.617021 (-875 1775);
PAINT BLUE (-875 1775);
FORCEPROP 1 LAST TOLERANCE 10%
J 2
(-875 1875);
DISPLAY 0.617021 (-875 1875);
PAINT SKYBLUE (-875 1875);
FORCEPROP 1 LAST VOLTAGE 16V
J 2
(-875 1925);
DISPLAY 0.617021 (-875 1925);
PAINT SKYBLUE (-875 1925);
FORCEPROP 1 LAST VALUE 0.220UF
J 2
(-875 1975);
DISPLAY 0.617021 (-875 1975);
PAINT SKYBLUE (-875 1975);
FORCEPROP 1 LAST LOCATION C1A18
J 2
(-875 2025);
DISPLAY 0.617021 (-875 2025);
PAINT AQUA (-875 2025);
FORCEPROP 1 LASTPIN (-825 2025) $PN 1
J 2
(-835 2005);
DISPLAY 0.617021 (-835 2005);
PAINT ORANGE (-835 2005);
FORCEPROP 1 LASTPIN (-825 1825) $PN 2
J 2
(-835 1805);
DISPLAY 0.617021 (-835 1805);
PAINT ORANGE (-835 1805);
FORCEPROP 1 LAST MATERIAL X7R
J 2
(-875 1825);
DISPLAY 0.617021 (-875 1825);
PAINT SKYBLUE (-875 1825);
FORCEPROP 1 LAST PACK_TYPE 0402
J 2
(-875 1725);
DISPLAY 0.617021 (-875 1725);
PAINT SKYBLUE (-875 1725);
FORCEPROP 2 LAST SEC_TYPE 0402
J 0
(-875 2125);
DISPLAY 1.021277 (-875 2125);
PAINT ORANGE (-875 2125);
DISPLAY INVISIBLE (-875 2125);
FORCEPROP 0 LAST SPOF TRUE
J 0
(-875 2125);
DISPLAY 1.021277 (-875 2125);
PAINT ORANGE (-875 2125);
DISPLAY INVISIBLE (-875 2125);
FORCEPROP 2 LAST SEC 1
J 0
(-875 2125);
DISPLAY 0.680851 (-875 2125);
PAINT MONO (-875 2125);
DISPLAY INVISIBLE (-875 2125);
FORCEPROP 2 LAST ROOM VDDQ_KLM_PWR_VR
J 0
(-900 2075);
DISPLAY 1.361702 (-900 2075);
PAINT ORANGE (-900 2075);
DISPLAY INVISIBLE (-900 2075);
FORCEPROP 1 LAST PATH I44
J 2
(-875 2075);
DISPLAY 0.978723 (-875 2075);
PAINT WHITE (-875 2075);
DISPLAY INVISIBLE (-875 2075);
FORCEPROP 2 LAST CDS_LOCATION C1A18
J 2
(-875 2025);
DISPLAY 0.617021 (-875 2025);
PAINT AQUA (-875 2025);
DISPLAY INVISIBLE (-875 2025);
FORCEPROP 2 LAST CDS_LIB mstr_discrete
J 0
(-825 1925);
PAINT ORANGE (-825 1925);
DISPLAY INVISIBLE (-825 1925);
FORCEADD CAP..1
(-2250 2500);
FORCEPROP 1 LAST LOCATION C9L11
J 0
(-2200 2600);
DISPLAY 0.617021 (-2200 2600);
PAINT AQUA (-2200 2600);
FORCEPROP 1 LAST VOLTAGE 16V
J 0
(-2200 2500);
DISPLAY 0.617021 (-2200 2500);
PAINT SKYBLUE (-2200 2500);
FORCEPROP 1 LAST VALUE 10UF
J 0
(-2200 2550);
DISPLAY 0.617021 (-2200 2550);
PAINT SKYBLUE (-2200 2550);
FORCEPROP 1 LASTPIN (-2250 2600) $PN 1
J 0
(-2240 2580);
DISPLAY 0.617021 (-2240 2580);
PAINT ORANGE (-2240 2580);
FORCEPROP 1 LAST PACK_TYPE 0805
J 0
(-2200 2300);
DISPLAY 0.617021 (-2200 2300);
PAINT SKYBLUE (-2200 2300);
FORCEPROP 1 LASTPIN (-2250 2400) $PN 2
J 0
(-2240 2380);
DISPLAY 0.617021 (-2240 2380);
PAINT ORANGE (-2240 2380);
FORCEPROP 1 LAST TOLERANCE 10%
J 0
(-2200 2450);
DISPLAY 0.617021 (-2200 2450);
PAINT SKYBLUE (-2200 2450);
FORCEPROP 1 LAST MATERIAL X6S
J 0
(-2200 2400);
DISPLAY 0.617021 (-2200 2400);
PAINT SKYBLUE (-2200 2400);
FORCEPROP 1 LAST PART_NUMBER C95333-007
J 0
(-2200 2350);
DISPLAY 0.617021 (-2200 2350);
PAINT BLUE (-2200 2350);
FORCEPROP 2 LAST CDS_LIB mstr_discrete
J 0
(-2250 2500);
PAINT ORANGE (-2250 2500);
DISPLAY INVISIBLE (-2250 2500);
FORCEPROP 2 LAST CDS_LOCATION C9L11
J 0
(-2200 2600);
DISPLAY 0.617021 (-2200 2600);
PAINT AQUA (-2200 2600);
DISPLAY INVISIBLE (-2200 2600);
FORCEPROP 2 LAST ROOM VDDQ_KLM_PWR_VR
J 0
(-2200 2650);
DISPLAY 1.361702 (-2200 2650);
PAINT ORANGE (-2200 2650);
DISPLAY INVISIBLE (-2200 2650);
FORCEPROP 1 LAST PATH I45
J 0
(-2200 2650);
DISPLAY 1.319149 (-2200 2650);
PAINT WHITE (-2200 2650);
DISPLAY INVISIBLE (-2200 2650);
FORCEPROP 2 LAST SEC 1
J 0
(-2200 2725);
DISPLAY 0.680851 (-2200 2725);
PAINT MONO (-2200 2725);
DISPLAY INVISIBLE (-2200 2725);
FORCEPROP 2 LAST SEC_TYPE 0805
J 0
(-2200 2725);
DISPLAY 1.021277 (-2200 2725);
PAINT ORANGE (-2200 2725);
DISPLAY INVISIBLE (-2200 2725);
FORCEADD CAP..1
(-1975 2500);
FORCEPROP 1 LAST LOCATION C9L10
J 0
(-1925 2600);
DISPLAY 0.617021 (-1925 2600);
PAINT AQUA (-1925 2600);
FORCEPROP 1 LAST VOLTAGE 16V
J 0
(-1925 2500);
DISPLAY 0.617021 (-1925 2500);
PAINT SKYBLUE (-1925 2500);
FORCEPROP 1 LASTPIN (-1975 2600) $PN 1
J 0
(-1965 2580);
DISPLAY 0.617021 (-1965 2580);
PAINT ORANGE (-1965 2580);
FORCEPROP 1 LAST TOLERANCE 10%
J 0
(-1925 2450);
DISPLAY 0.617021 (-1925 2450);
PAINT SKYBLUE (-1925 2450);
FORCEPROP 1 LAST VALUE 10UF
J 0
(-1925 2550);
DISPLAY 0.617021 (-1925 2550);
PAINT SKYBLUE (-1925 2550);
FORCEPROP 1 LASTPIN (-1975 2400) $PN 2
J 0
(-1965 2380);
DISPLAY 0.617021 (-1965 2380);
PAINT ORANGE (-1965 2380);
FORCEPROP 1 LAST MATERIAL X6S
J 0
(-1925 2400);
DISPLAY 0.617021 (-1925 2400);
PAINT SKYBLUE (-1925 2400);
FORCEPROP 1 LAST PART_NUMBER C95333-007
J 0
(-1925 2350);
DISPLAY 0.617021 (-1925 2350);
PAINT BLUE (-1925 2350);
FORCEPROP 1 LAST PACK_TYPE 0805
J 0
(-1925 2300);
DISPLAY 0.617021 (-1925 2300);
PAINT SKYBLUE (-1925 2300);
FORCEPROP 2 LAST CDS_LIB mstr_discrete
J 0
(-1975 2500);
PAINT ORANGE (-1975 2500);
DISPLAY INVISIBLE (-1975 2500);
FORCEPROP 2 LAST CDS_LOCATION C9L10
J 0
(-1925 2600);
DISPLAY 0.617021 (-1925 2600);
PAINT AQUA (-1925 2600);
DISPLAY INVISIBLE (-1925 2600);
FORCEPROP 2 LAST ROOM VDDQ_KLM_PWR_VR
J 0
(-1925 2650);
DISPLAY 1.361702 (-1925 2650);
PAINT ORANGE (-1925 2650);
DISPLAY INVISIBLE (-1925 2650);
FORCEPROP 1 LAST PATH I46
J 0
(-1925 2650);
DISPLAY 1.319149 (-1925 2650);
PAINT WHITE (-1925 2650);
DISPLAY INVISIBLE (-1925 2650);
FORCEPROP 2 LAST SEC_TYPE 0805
J 0
(-1925 2725);
DISPLAY 1.021277 (-1925 2725);
PAINT ORANGE (-1925 2725);
DISPLAY INVISIBLE (-1925 2725);
FORCEPROP 2 LAST SEC 1
J 0
(-1925 2725);
DISPLAY 0.680851 (-1925 2725);
PAINT MONO (-1925 2725);
DISPLAY INVISIBLE (-1925 2725);
FORCEADD CAP..1
(-1700 2500);
FORCEPROP 1 LAST VOLTAGE 16V
J 0
(-1650 2500);
DISPLAY 0.617021 (-1650 2500);
PAINT SKYBLUE (-1650 2500);
FORCEPROP 1 LAST TOLERANCE 10%
J 0
(-1650 2450);
DISPLAY 0.617021 (-1650 2450);
PAINT SKYBLUE (-1650 2450);
FORCEPROP 1 LASTPIN (-1700 2400) $PN 2
J 0
(-1690 2380);
DISPLAY 0.617021 (-1690 2380);
PAINT ORANGE (-1690 2380);
FORCEPROP 1 LASTPIN (-1700 2600) $PN 1
J 0
(-1690 2580);
DISPLAY 0.617021 (-1690 2580);
PAINT ORANGE (-1690 2580);
FORCEPROP 1 LAST MATERIAL X6S
J 0
(-1650 2400);
DISPLAY 0.617021 (-1650 2400);
PAINT SKYBLUE (-1650 2400);
FORCEPROP 1 LAST PACK_TYPE 0805
J 0
(-1650 2300);
DISPLAY 0.617021 (-1650 2300);
PAINT SKYBLUE (-1650 2300);
FORCEPROP 1 LAST VALUE 10UF
J 0
(-1650 2550);
DISPLAY 0.617021 (-1650 2550);
PAINT SKYBLUE (-1650 2550);
FORCEPROP 1 LAST PART_NUMBER C95333-007
J 0
(-1650 2350);
DISPLAY 0.617021 (-1650 2350);
PAINT BLUE (-1650 2350);
FORCEPROP 1 LAST LOCATION C9L6
J 0
(-1650 2600);
DISPLAY 0.617021 (-1650 2600);
PAINT AQUA (-1650 2600);
FORCEPROP 2 LAST CDS_LIB mstr_discrete
J 0
(-1700 2500);
PAINT ORANGE (-1700 2500);
DISPLAY INVISIBLE (-1700 2500);
FORCEPROP 2 LAST CDS_LOCATION C9L6
J 0
(-1650 2600);
DISPLAY 0.617021 (-1650 2600);
PAINT AQUA (-1650 2600);
DISPLAY INVISIBLE (-1650 2600);
FORCEPROP 2 LAST SEC_TYPE 0805
J 0
(-1650 2725);
DISPLAY 1.021277 (-1650 2725);
PAINT ORANGE (-1650 2725);
DISPLAY INVISIBLE (-1650 2725);
FORCEPROP 2 LAST SEC 1
J 0
(-1650 2725);
DISPLAY 0.680851 (-1650 2725);
PAINT MONO (-1650 2725);
DISPLAY INVISIBLE (-1650 2725);
FORCEPROP 1 LAST PATH I47
J 0
(-1650 2650);
DISPLAY 1.319149 (-1650 2650);
PAINT WHITE (-1650 2650);
DISPLAY INVISIBLE (-1650 2650);
FORCEPROP 2 LAST ROOM VDDQ_KLM_PWR_VR
J 0
(-1650 2650);
DISPLAY 1.361702 (-1650 2650);
PAINT ORANGE (-1650 2650);
DISPLAY INVISIBLE (-1650 2650);
FORCEADD CAP..1
(-1425 2475);
FORCEPROP 1 LAST VOLTAGE 16V
J 0
(-1375 2475);
DISPLAY 0.617021 (-1375 2475);
PAINT SKYBLUE (-1375 2475);
FORCEPROP 1 LAST LOCATION C1A19
J 0
(-1375 2575);
DISPLAY 0.617021 (-1375 2575);
PAINT AQUA (-1375 2575);
FORCEPROP 1 LAST PART_NUMBER D97712-011
J 0
(-1375 2325);
DISPLAY 0.617021 (-1375 2325);
PAINT BLUE (-1375 2325);
FORCEPROP 1 LAST TOLERANCE 10%
J 0
(-1375 2425);
DISPLAY 0.617021 (-1375 2425);
PAINT SKYBLUE (-1375 2425);
FORCEPROP 1 LAST PACK_TYPE 0402
J 0
(-1375 2275);
DISPLAY 0.617021 (-1375 2275);
PAINT SKYBLUE (-1375 2275);
FORCEPROP 1 LAST MATERIAL X6S
J 0
(-1375 2375);
DISPLAY 0.617021 (-1375 2375);
PAINT SKYBLUE (-1375 2375);
FORCEPROP 1 LASTPIN (-1425 2375) $PN 2
J 0
(-1415 2355);
DISPLAY 0.617021 (-1415 2355);
PAINT ORANGE (-1415 2355);
FORCEPROP 1 LASTPIN (-1425 2575) $PN 1
J 0
(-1415 2555);
DISPLAY 0.617021 (-1415 2555);
PAINT ORANGE (-1415 2555);
FORCEPROP 1 LAST VALUE 1.0UF
J 0
(-1375 2525);
DISPLAY 0.617021 (-1375 2525);
PAINT SKYBLUE (-1375 2525);
FORCEPROP 2 LAST ROOM VDDQ_KLM_PWR_VR
J 0
(-1375 2625);
DISPLAY 1.361702 (-1375 2625);
PAINT ORANGE (-1375 2625);
DISPLAY INVISIBLE (-1375 2625);
FORCEPROP 1 LAST PATH I48
J 0
(-1375 2625);
DISPLAY 1.319149 (-1375 2625);
PAINT WHITE (-1375 2625);
DISPLAY INVISIBLE (-1375 2625);
FORCEPROP 2 LAST SEC 1
J 0
(-1375 2700);
DISPLAY 0.680851 (-1375 2700);
PAINT MONO (-1375 2700);
DISPLAY INVISIBLE (-1375 2700);
FORCEPROP 2 LAST SEC_TYPE 0402
J 0
(-1375 2700);
DISPLAY 1.021277 (-1375 2700);
PAINT ORANGE (-1375 2700);
DISPLAY INVISIBLE (-1375 2700);
FORCEPROP 2 LAST CDS_LIB mstr_discrete
J 0
(-1425 2475);
PAINT ORANGE (-1425 2475);
DISPLAY INVISIBLE (-1425 2475);
FORCEPROP 2 LAST CDS_LOCATION C1A19
J 0
(-1375 2575);
DISPLAY 0.617021 (-1375 2575);
PAINT AQUA (-1375 2575);
DISPLAY INVISIBLE (-1375 2575);
FORCEADD CAP..1
(-900 2500);
FORCEPROP 1 LAST PACK_TYPE 0402
J 0
(-850 2300);
DISPLAY 0.617021 (-850 2300);
PAINT SKYBLUE (-850 2300);
FORCEPROP 1 LAST PART_NUMBER D97712-011
J 0
(-850 2350);
DISPLAY 0.617021 (-850 2350);
PAINT BLUE (-850 2350);
FORCEPROP 1 LASTPIN (-900 2400) $PN 2
J 0
(-890 2380);
DISPLAY 0.617021 (-890 2380);
PAINT ORANGE (-890 2380);
FORCEPROP 1 LAST VOLTAGE 16V
J 0
(-850 2500);
DISPLAY 0.617021 (-850 2500);
PAINT SKYBLUE (-850 2500);
FORCEPROP 1 LAST VALUE 1.0UF
J 0
(-850 2550);
DISPLAY 0.617021 (-850 2550);
PAINT SKYBLUE (-850 2550);
FORCEPROP 1 LAST MATERIAL X6S
J 0
(-850 2400);
DISPLAY 0.617021 (-850 2400);
PAINT SKYBLUE (-850 2400);
FORCEPROP 1 LASTPIN (-900 2600) $PN 1
J 0
(-890 2580);
DISPLAY 0.617021 (-890 2580);
PAINT ORANGE (-890 2580);
FORCEPROP 1 LAST LOCATION C1B20
J 0
(-850 2600);
DISPLAY 0.617021 (-850 2600);
PAINT AQUA (-850 2600);
FORCEPROP 1 LAST TOLERANCE 10%
J 0
(-850 2450);
DISPLAY 0.617021 (-850 2450);
PAINT SKYBLUE (-850 2450);
FORCEPROP 2 LAST CDS_LIB mstr_discrete
J 0
(-900 2500);
PAINT ORANGE (-900 2500);
DISPLAY INVISIBLE (-900 2500);
FORCEPROP 2 LAST ROOM VDDQ_KLM_PWR_VR
J 0
(-850 2650);
DISPLAY 1.361702 (-850 2650);
PAINT ORANGE (-850 2650);
DISPLAY INVISIBLE (-850 2650);
FORCEPROP 1 LAST PATH I50
J 0
(-850 2650);
DISPLAY 1.319149 (-850 2650);
PAINT WHITE (-850 2650);
DISPLAY INVISIBLE (-850 2650);
FORCEPROP 2 LAST SEC 1
J 0
(-850 2725);
DISPLAY 0.680851 (-850 2725);
PAINT MONO (-850 2725);
DISPLAY INVISIBLE (-850 2725);
FORCEPROP 2 LAST SEC_TYPE 0402
J 0
(-850 2725);
DISPLAY 1.021277 (-850 2725);
PAINT ORANGE (-850 2725);
DISPLAY INVISIBLE (-850 2725);
FORCEADD CAP_A..1
(-1175 2475);
FORCEPROP 1 LAST PACK_TYPE 0402V
J 0
(-1125 2275);
DISPLAY 0.617021 (-1125 2275);
PAINT SKYBLUE (-1125 2275);
FORCEPROP 1 LAST PART_NUMBER A36096-030
J 0
(-1125 2325);
DISPLAY 0.617021 (-1125 2325);
PAINT BLUE (-1125 2325);
FORCEPROP 1 LAST MATERIAL X7R
J 0
(-1125 2375);
DISPLAY 0.617021 (-1125 2375);
PAINT SKYBLUE (-1125 2375);
FORCEPROP 1 LAST TOLERANCE 10%
J 0
(-1125 2425);
DISPLAY 0.617021 (-1125 2425);
PAINT SKYBLUE (-1125 2425);
FORCEPROP 1 LAST VALUE 0.1UF
J 0
(-1125 2525);
DISPLAY 0.617021 (-1125 2525);
PAINT SKYBLUE (-1125 2525);
FORCEPROP 1 LAST LOCATION C1A10
J 0
(-1125 2575);
DISPLAY 0.617021 (-1125 2575);
PAINT AQUA (-1125 2575);
FORCEPROP 1 LASTPIN (-1175 2575) $PN 1
J 0
(-1165 2555);
DISPLAY 0.617021 (-1165 2555);
PAINT ORANGE (-1165 2555);
FORCEPROP 1 LASTPIN (-1175 2375) $PN 2
J 0
(-1165 2355);
DISPLAY 0.617021 (-1165 2355);
PAINT ORANGE (-1165 2355);
FORCEPROP 1 LAST VOLTAGE 16V
J 0
(-1125 2475);
DISPLAY 0.617021 (-1125 2475);
PAINT SKYBLUE (-1125 2475);
FORCEPROP 2 LAST SEC 1
J 0
(-1125 2700);
DISPLAY 0.680851 (-1125 2700);
PAINT MONO (-1125 2700);
DISPLAY INVISIBLE (-1125 2700);
FORCEPROP 2 LAST SEC_TYPE 0402V
J 0
(-1125 2700);
DISPLAY 1.021277 (-1125 2700);
PAINT ORANGE (-1125 2700);
DISPLAY INVISIBLE (-1125 2700);
FORCEPROP 1 LAST PATH I51
J 0
(-1125 2625);
DISPLAY 0.978723 (-1125 2625);
PAINT WHITE (-1125 2625);
DISPLAY INVISIBLE (-1125 2625);
FORCEPROP 2 LAST ROOM VDDQ_KLM_PWR_VR
J 0
(-1125 2625);
DISPLAY 1.361702 (-1125 2625);
PAINT ORANGE (-1125 2625);
DISPLAY INVISIBLE (-1125 2625);
FORCEPROP 2 LAST CDS_SEC 1
J 0
(-1125 2625);
PAINT ORANGE (-1125 2625);
DISPLAY INVISIBLE (-1125 2625);
FORCEPROP 2 LAST CDS_LIB dev_discrete
J 0
(-1175 2475);
PAINT ORANGE (-1175 2475);
DISPLAY INVISIBLE (-1175 2475);
FORCEPROP 2 LAST CDS_LOCATION C1A10
J 0
(-1125 2575);
DISPLAY 0.617021 (-1125 2575);
PAINT AQUA (-1125 2575);
DISPLAY INVISIBLE (-1125 2575);
FORCEADD CAP..1
(-100 2475);
FORCEPROP 1 LAST PART_NUMBER A36096-155
J 0
(-50 2325);
DISPLAY 0.617021 (-50 2325);
PAINT BLUE (-50 2325);
FORCEPROP 1 LAST VOLTAGE 16V
J 0
(-50 2475);
DISPLAY 0.617021 (-50 2475);
PAINT SKYBLUE (-50 2475);
FORCEPROP 1 LAST PACK_TYPE 0402
J 0
(-50 2275);
DISPLAY 0.617021 (-50 2275);
PAINT SKYBLUE (-50 2275);
FORCEPROP 1 LAST VALUE 0.22UF
J 0
(-50 2525);
DISPLAY 0.617021 (-50 2525);
PAINT SKYBLUE (-50 2525);
FORCEPROP 1 LAST TOLERANCE 10%
J 0
(-50 2425);
DISPLAY 0.617021 (-50 2425);
PAINT SKYBLUE (-50 2425);
FORCEPROP 1 LAST MATERIAL X7R
J 0
(-50 2375);
DISPLAY 0.617021 (-50 2375);
PAINT SKYBLUE (-50 2375);
FORCEPROP 1 LASTPIN (-100 2375) $PN 2
J 0
(-90 2355);
DISPLAY 0.617021 (-90 2355);
PAINT ORANGE (-90 2355);
FORCEPROP 1 LASTPIN (-100 2575) $PN 1
J 0
(-90 2555);
DISPLAY 0.617021 (-90 2555);
PAINT ORANGE (-90 2555);
FORCEPROP 1 LAST LOCATION C1B21
J 0
(-50 2575);
DISPLAY 0.617021 (-50 2575);
PAINT AQUA (-50 2575);
FORCEPROP 2 LAST CDS_LIB mstr_discrete
J 0
(-100 2475);
PAINT ORANGE (-100 2475);
DISPLAY INVISIBLE (-100 2475);
FORCEPROP 2 LAST ROOM VDDQ_KLM_PWR_VR
J 0
(-50 2625);
DISPLAY 1.361702 (-50 2625);
PAINT ORANGE (-50 2625);
DISPLAY INVISIBLE (-50 2625);
FORCEPROP 1 LAST PATH I54
J 0
(-50 2625);
DISPLAY 1.319149 (-50 2625);
PAINT WHITE (-50 2625);
DISPLAY INVISIBLE (-50 2625);
FORCEPROP 2 LAST SEC 1
J 0
(-50 2700);
DISPLAY 0.680851 (-50 2700);
PAINT MONO (-50 2700);
DISPLAY INVISIBLE (-50 2700);
FORCEPROP 2 LAST SEC_TYPE 0402
J 0
(-50 2700);
DISPLAY 1.021277 (-50 2700);
PAINT ORANGE (-50 2700);
DISPLAY INVISIBLE (-50 2700);
FORCEADD OFFPAGE..2
(3625 2350);
FORCEPROP 2 LAST $XR1 226 
J 0
(3934 2350);
DISPLAY 0.638298 (3934 2350);
PAINT MONO (3934 2350);
FORCEPROP 2 LAST $XR0 227 
J 0
(3814 2350);
DISPLAY 0.638298 (3814 2350);
PAINT MONO (3814 2350);
FORCEPROP 1 LAST COMMENT_BODY TRUE
J 0
(3580 2255);
DISPLAY 1.723404 (3580 2255);
PAINT GREEN (3580 2255);
DISPLAY INVISIBLE (3580 2255);
FORCEPROP 1 LAST OFFPAGE TRUE
J 0
(3950 2225);
DISPLAY 1.723404 (3950 2225);
PAINT GREEN (3950 2225);
DISPLAY INVISIBLE (3950 2225);
FORCEPROP 2 LAST BOM_COST VDDQ_KLM_PWR_VR
J 0
(3825 2400);
DISPLAY 1.446809 (3825 2400);
PAINT MONO (3825 2400);
DISPLAY INVISIBLE (3825 2400);
FORCEPROP 2 LAST PATH I58
J 0
(3805 2425);
DISPLAY 1.361702 (3805 2425);
PAINT ORANGE (3805 2425);
DISPLAY INVISIBLE (3805 2425);
FORCEPROP 2 LAST CDS_LIB mstr_standard
J 0
(3625 2350);
PAINT ORANGE (3625 2350);
DISPLAY INVISIBLE (3625 2350);
FORCEPROP 2 LAST ROOM VDDQ_KLM_PWR_VR
J 0
(3225 2425);
DISPLAY 1.936170 (3225 2425);
PAINT ORANGE (3225 2425);
DISPLAY INVISIBLE (3225 2425);
FORCEADD CAP..1
(4350 1775);
FORCEPROP 1 LAST VALUE 22UF
J 0
(4400 1825);
DISPLAY 0.617021 (4400 1825);
PAINT SKYBLUE (4400 1825);
FORCEPROP 1 LAST VOLTAGE 4V
J 0
(4400 1775);
DISPLAY 0.723404 (4400 1775);
PAINT SKYBLUE (4400 1775);
FORCEPROP 1 LAST TOLERANCE 20%
J 0
(4400 1725);
DISPLAY 0.617021 (4400 1725);
PAINT SKYBLUE (4400 1725);
FORCEPROP 1 LASTPIN (4350 1675) $PN 2
J 0
(4360 1655);
DISPLAY 0.617021 (4360 1655);
PAINT GREEN (4360 1655);
FORCEPROP 1 LAST MATERIAL X6S
J 0
(4400 1675);
DISPLAY 0.617021 (4400 1675);
PAINT SKYBLUE (4400 1675);
FORCEPROP 1 LAST LOCATION C1A12
J 0
(4400 1875);
DISPLAY 0.617021 (4400 1875);
PAINT AQUA (4400 1875);
FORCEPROP 1 LASTPIN (4350 1875) $PN 1
J 0
(4360 1855);
DISPLAY 0.617021 (4360 1855);
PAINT GREEN (4360 1855);
FORCEPROP 1 LAST PACK_TYPE 0805LF
J 0
(4400 1575);
DISPLAY 0.617021 (4400 1575);
PAINT SKYBLUE (4400 1575);
FORCEPROP 1 LAST PART_NUMBER C95333-002
J 0
(4400 1625);
DISPLAY 0.617021 (4400 1625);
PAINT BLUE (4400 1625);
FORCEPROP 0 LAST GROUP PWR_MLCC_CAP
J 0
(4406 1537);
DISPLAY 0.638298 (4406 1537);
PAINT BROWN (4406 1537);
DISPLAY BOTH (4406 1537);
FORCEPROP 2 LAST BOM_COST VDDQ_KLM_PWR_VR
J 0
(4400 1925);
DISPLAY 1.446809 (4400 1925);
PAINT MONO (4400 1925);
DISPLAY INVISIBLE (4400 1925);
FORCEPROP 2 LAST SEC_TYPE 0805LF
J 0
(4405 1975);
DISPLAY 1.021277 (4405 1975);
PAINT ORANGE (4405 1975);
DISPLAY INVISIBLE (4405 1975);
FORCEPROP 2 LAST SEC 1
J 0
(4405 1975);
DISPLAY 0.680851 (4405 1975);
PAINT MONO (4405 1975);
DISPLAY INVISIBLE (4405 1975);
FORCEPROP 1 LAST PATH I6
J 0
(4400 1925);
DISPLAY 0.978723 (4400 1925);
PAINT WHITE (4400 1925);
DISPLAY INVISIBLE (4400 1925);
FORCEPROP 2 LAST ROOM VDDQ_KLM_PWR_VR
J 0
(4400 1925);
DISPLAY 1.446809 (4400 1925);
PAINT MONO (4400 1925);
DISPLAY INVISIBLE (4400 1925);
FORCEPROP 2 LAST CDS_LIB mstr_discrete
J 0
(4350 1775);
DISPLAY 1.936170 (4350 1775);
PAINT ORANGE (4350 1775);
DISPLAY INVISIBLE (4350 1775);
FORCEPROP 2 LAST CDS_LOCATION C1A12
J 0
(4400 1875);
DISPLAY 0.617021 (4400 1875);
PAINT AQUA (4400 1875);
DISPLAY INVISIBLE (4400 1875);
FORCEADD OFFPAGE..2
(3975 875);
FORCEPROP 2 LAST $XR0 226 
J 0
(4164 875);
DISPLAY 0.638298 (4164 875);
PAINT MONO (4164 875);
FORCEPROP 2 LAST ROOM VDDQ_KLM_PWR_VR
J 0
(3575 950);
DISPLAY 1.936170 (3575 950);
PAINT ORANGE (3575 950);
DISPLAY INVISIBLE (3575 950);
FORCEPROP 2 LAST CDS_LIB mstr_standard
J 0
(3975 875);
PAINT ORANGE (3975 875);
DISPLAY INVISIBLE (3975 875);
FORCEPROP 2 LAST PATH I61
J 0
(4155 950);
DISPLAY 1.361702 (4155 950);
PAINT ORANGE (4155 950);
DISPLAY INVISIBLE (4155 950);
FORCEPROP 2 LAST BOM_COST VDDQ_KLM_PWR_VR
J 0
(4175 925);
DISPLAY 1.446809 (4175 925);
PAINT MONO (4175 925);
DISPLAY INVISIBLE (4175 925);
FORCEPROP 1 LAST OFFPAGE TRUE
J 0
(4300 750);
DISPLAY 1.723404 (4300 750);
PAINT GREEN (4300 750);
DISPLAY INVISIBLE (4300 750);
FORCEPROP 1 LAST COMMENT_BODY TRUE
J 0
(3930 780);
DISPLAY 1.723404 (3930 780);
PAINT GREEN (3930 780);
DISPLAY INVISIBLE (3930 780);
FORCEADD OFFPAGE..2
(3950 525);
FORCEPROP 2 LAST $XR0 226 
J 0
(4139 525);
DISPLAY 0.638298 (4139 525);
PAINT MONO (4139 525);
FORCEPROP 2 LAST ROOM VDDQ_KLM_PWR_VR
J 0
(3550 600);
DISPLAY 1.936170 (3550 600);
PAINT ORANGE (3550 600);
DISPLAY INVISIBLE (3550 600);
FORCEPROP 2 LAST CDS_LIB mstr_standard
J 0
(3950 525);
PAINT ORANGE (3950 525);
DISPLAY INVISIBLE (3950 525);
FORCEPROP 2 LAST PATH I62
J 0
(4130 600);
DISPLAY 1.361702 (4130 600);
PAINT ORANGE (4130 600);
DISPLAY INVISIBLE (4130 600);
FORCEPROP 2 LAST BOM_COST VDDQ_KLM_PWR_VR
J 0
(4150 575);
DISPLAY 1.446809 (4150 575);
PAINT MONO (4150 575);
DISPLAY INVISIBLE (4150 575);
FORCEPROP 1 LAST OFFPAGE TRUE
J 0
(4275 400);
DISPLAY 1.723404 (4275 400);
PAINT GREEN (4275 400);
DISPLAY INVISIBLE (4275 400);
FORCEPROP 1 LAST COMMENT_BODY TRUE
J 0
(3905 430);
DISPLAY 1.723404 (3905 430);
PAINT GREEN (3905 430);
DISPLAY INVISIBLE (3905 430);
FORCEADD OFFPAGE..2
(3475 175);
FORCEPROP 2 LAST $XR1 226 
J 0
(3784 175);
DISPLAY 0.638298 (3784 175);
PAINT MONO (3784 175);
FORCEPROP 2 LAST $XR0 227 
J 0
(3664 175);
DISPLAY 0.638298 (3664 175);
PAINT MONO (3664 175);
FORCEPROP 2 LAST BOM_COST VDDQ_KLM_PWR_VR
J 0
(3675 225);
DISPLAY 1.446809 (3675 225);
PAINT MONO (3675 225);
DISPLAY INVISIBLE (3675 225);
FORCEPROP 2 LAST PATH I63
J 0
(3655 250);
DISPLAY 1.361702 (3655 250);
PAINT ORANGE (3655 250);
DISPLAY INVISIBLE (3655 250);
FORCEPROP 2 LAST CDS_LIB mstr_standard
J 0
(3475 175);
PAINT ORANGE (3475 175);
DISPLAY INVISIBLE (3475 175);
FORCEPROP 2 LAST ROOM VDDQ_KLM_PWR_VR
J 0
(3075 250);
DISPLAY 1.936170 (3075 250);
PAINT ORANGE (3075 250);
DISPLAY INVISIBLE (3075 250);
FORCEPROP 1 LAST OFFPAGE TRUE
J 0
(3800 50);
DISPLAY 1.723404 (3800 50);
PAINT GREEN (3800 50);
DISPLAY INVISIBLE (3800 50);
FORCEPROP 1 LAST COMMENT_BODY TRUE
J 0
(3430 80);
DISPLAY 1.723404 (3430 80);
PAINT GREEN (3430 80);
DISPLAY INVISIBLE (3430 80);
FORCEADD PVDDQ_KLM..1
(4375 -225);
FORCEPROP 3 LASTPIN (4375 -275) SIG_NAME PVDDQ_KLM\g
J 0
(4385 -265);
DISPLAY 0.659574 (4385 -265);
PAINT MONO (4385 -265);
DISPLAY INVISIBLE (4385 -265);
FORCEPROP 1 LAST VOLTAGE 1.2V
J 0
(4330 -268);
DISPLAY 0.340426 (4330 -268);
PAINT SKYBLUE (4330 -268);
DISPLAY INVISIBLE (4330 -268);
FORCEPROP 2 LAST BOM_COST VDDQ_KLM_PWR_VR
J 0
(4375 -125);
DISPLAY 1.446809 (4375 -125);
PAINT MONO (4375 -125);
DISPLAY INVISIBLE (4375 -125);
FORCEPROP 2 LAST CDS_LIB mstr_symbols
J 0
(4375 -225);
PAINT ORANGE (4375 -225);
DISPLAY INVISIBLE (4375 -225);
FORCEPROP 1 LAST PATH I64
J 0
(4425 -200);
DISPLAY 0.872340 (4425 -200);
PAINT AQUA (4425 -200);
DISPLAY INVISIBLE (4425 -200);
FORCEPROP 2 LAST ROOM VDDQ_KLM_PWR_VR
J 0
(4375 -125);
DISPLAY 1.936170 (4375 -125);
PAINT ORANGE (4375 -125);
DISPLAY INVISIBLE (4375 -125);
FORCEPROP 1 LAST BODY_TYPE PLUMBING
J 0
(4330 -268);
DISPLAY 0.340426 (4330 -268);
PAINT GREEN (4330 -268);
DISPLAY INVISIBLE (4330 -268);
FORCEPROP 1 LAST HDL_POWER PVDDQ_KLM
J 1
(4375 -175);
DISPLAY 0.872340 (4375 -175);
PAINT GREEN (4375 -175);
DISPLAY INVISIBLE (4375 -175);
FORCEADD CAP..1
(4375 -475);
FORCEPROP 1 LAST MATERIAL X6S
J 0
(4425 -575);
DISPLAY 0.617021 (4425 -575);
PAINT SKYBLUE (4425 -575);
FORCEPROP 1 LAST VALUE 22UF
J 0
(4425 -425);
DISPLAY 0.617021 (4425 -425);
PAINT SKYBLUE (4425 -425);
FORCEPROP 1 LAST LOCATION C1A1
J 0
(4425 -375);
DISPLAY 0.617021 (4425 -375);
PAINT AQUA (4425 -375);
FORCEPROP 1 LASTPIN (4375 -375) $PN 1
J 0
(4385 -395);
DISPLAY 0.617021 (4385 -395);
PAINT ORANGE (4385 -395);
FORCEPROP 1 LASTPIN (4375 -575) $PN 2
J 0
(4385 -595);
DISPLAY 0.617021 (4385 -595);
PAINT ORANGE (4385 -595);
FORCEPROP 1 LAST TOLERANCE 20%
J 0
(4425 -525);
DISPLAY 0.617021 (4425 -525);
PAINT SKYBLUE (4425 -525);
FORCEPROP 1 LAST PACK_TYPE 0805LF
J 0
(4425 -675);
DISPLAY 0.617021 (4425 -675);
PAINT SKYBLUE (4425 -675);
FORCEPROP 1 LAST VOLTAGE 4V
J 0
(4425 -475);
DISPLAY 0.574468 (4425 -475);
PAINT SKYBLUE (4425 -475);
FORCEPROP 1 LAST PART_NUMBER C95333-002
J 0
(4425 -625);
DISPLAY 0.617021 (4425 -625);
PAINT BLUE (4425 -625);
FORCEPROP 0 LAST BOM_SS NOPOP
J 0
(4425 -750);
DISPLAY 0.638298 (4425 -750);
PAINT BROWN (4425 -750);
DISPLAY BOTH (4425 -750);
FORCEPROP 0 LAST GROUP PWR_MLCC_CAP
J 0
(4431 -713);
DISPLAY 0.638298 (4431 -713);
PAINT BROWN (4431 -713);
DISPLAY BOTH (4431 -713);
FORCEPROP 2 LAST CDS_LIB mstr_discrete
J 0
(4375 -475);
PAINT ORANGE (4375 -475);
DISPLAY INVISIBLE (4375 -475);
FORCEPROP 2 LAST ROOM VDDQ_KLM_PWR_VR
J 0
(4425 -325);
DISPLAY 1.446809 (4425 -325);
PAINT MONO (4425 -325);
DISPLAY INVISIBLE (4425 -325);
FORCEPROP 1 LAST PATH I68
J 0
(4425 -325);
DISPLAY 1.319149 (4425 -325);
PAINT WHITE (4425 -325);
DISPLAY INVISIBLE (4425 -325);
FORCEPROP 2 LAST CDS_LOCATION C1A1
J 0
(4425 -375);
DISPLAY 0.617021 (4425 -375);
PAINT AQUA (4425 -375);
DISPLAY INVISIBLE (4425 -375);
FORCEPROP 2 LAST BOM_COST VDDQ_KLM_PWR_VR
J 0
(4425 -325);
DISPLAY 1.446809 (4425 -325);
PAINT MONO (4425 -325);
DISPLAY INVISIBLE (4425 -325);
FORCEPROP 2 LAST SEC_TYPE 0805LF
J 0
(4430 -250);
DISPLAY 1.021277 (4430 -250);
PAINT ORANGE (4430 -250);
DISPLAY INVISIBLE (4430 -250);
FORCEPROP 2 LAST SEC 1
J 0
(4430 -250);
DISPLAY 0.680851 (4430 -250);
PAINT MONO (4430 -250);
DISPLAY INVISIBLE (4430 -250);
FORCEADD GND..1
(4375 -650);
FORCEPROP 3 LASTPIN (4375 -600) SIG_NAME GND\g
J 0
(4385 -590);
DISPLAY 0.659574 (4385 -590);
PAINT MONO (4385 -590);
DISPLAY INVISIBLE (4385 -590);
FORCEPROP 1 LAST HDL_POWER GND
J 0
(4375 -500);
DISPLAY 1.723404 (4375 -500);
PAINT GREEN (4375 -500);
DISPLAY INVISIBLE (4375 -500);
FORCEPROP 1 LAST BODY_TYPE PLUMBING
J 0
(4330 -693);
DISPLAY 0.340426 (4330 -693);
PAINT GREEN (4330 -693);
DISPLAY INVISIBLE (4330 -693);
FORCEPROP 2 LAST ROOM VDDQ_KLM_PWR_VR
J 0
(3825 -575);
DISPLAY 1.936170 (3825 -575);
PAINT ORANGE (3825 -575);
DISPLAY INVISIBLE (3825 -575);
FORCEPROP 2 LAST BOM_COST VDDQ_KLM_PWR_VR
J 0
(4000 -575);
DISPLAY 1.446809 (4000 -575);
PAINT MONO (4000 -575);
DISPLAY INVISIBLE (4000 -575);
FORCEPROP 2 LAST CDS_LIB mstr_symbols
J 0
(4375 -650);
PAINT ORANGE (4375 -650);
DISPLAY INVISIBLE (4375 -650);
FORCEPROP 1 LAST VOLTAGE 0
J 0
(4375 -650);
PAINT SKYBLUE (4375 -650);
DISPLAY INVISIBLE (4375 -650);
FORCEPROP 1 LAST PATH I69
J 0
(4450 -650);
DISPLAY 1.170213 (4450 -650);
PAINT AQUA (4450 -650);
DISPLAY INVISIBLE (4450 -650);
FORCEPROP 1 LAST SIZE 1B
J 0
(4450 -700);
DISPLAY 1.723404 (4450 -700);
PAINT GREEN (4450 -700);
DISPLAY INVISIBLE (4450 -700);
FORCEADD GND..1
(4350 1600);
FORCEPROP 3 LASTPIN (4350 1650) SIG_NAME GND\g
J 0
(4360 1660);
DISPLAY 0.659574 (4360 1660);
PAINT MONO (4360 1660);
DISPLAY INVISIBLE (4360 1660);
FORCEPROP 1 LAST SIZE 1B
J 0
(4425 1550);
DISPLAY 1.723404 (4425 1550);
PAINT GREEN (4425 1550);
DISPLAY INVISIBLE (4425 1550);
FORCEPROP 1 LAST PATH I7
J 0
(4425 1600);
DISPLAY 0.893617 (4425 1600);
PAINT AQUA (4425 1600);
DISPLAY INVISIBLE (4425 1600);
FORCEPROP 2 LAST BOM_COST VDDQ_KLM_PWR_VR
J 0
(3975 1675);
DISPLAY 1.446809 (3975 1675);
PAINT MONO (3975 1675);
DISPLAY INVISIBLE (3975 1675);
FORCEPROP 1 LAST VOLTAGE 0
J 0
(4350 1600);
PAINT SKYBLUE (4350 1600);
DISPLAY INVISIBLE (4350 1600);
FORCEPROP 2 LAST CDS_LIB mstr_symbols
J 0
(4350 1600);
DISPLAY 1.936170 (4350 1600);
PAINT ORANGE (4350 1600);
DISPLAY INVISIBLE (4350 1600);
FORCEPROP 2 LAST ROOM VDDQ_KLM_PWR_VR
J 0
(3800 1675);
DISPLAY 1.936170 (3800 1675);
PAINT ORANGE (3800 1675);
DISPLAY INVISIBLE (3800 1675);
FORCEPROP 1 LAST BODY_TYPE PLUMBING
J 0
(4305 1557);
DISPLAY 0.340426 (4305 1557);
PAINT GREEN (4305 1557);
DISPLAY INVISIBLE (4305 1557);
FORCEPROP 1 LAST HDL_POWER GND
J 0
(4350 1750);
DISPLAY 1.723404 (4350 1750);
PAINT GREEN (4350 1750);
DISPLAY INVISIBLE (4350 1750);
FORCEADD GND..1
(2700 -775);
FORCEPROP 3 LASTPIN (2700 -725) SIG_NAME GND\g
J 0
(2710 -715);
DISPLAY 0.659574 (2710 -715);
PAINT MONO (2710 -715);
DISPLAY INVISIBLE (2710 -715);
FORCEPROP 2 LAST ROOM VDDQ_KLM_PWR_VR
J 0
(2150 -700);
DISPLAY 1.936170 (2150 -700);
PAINT ORANGE (2150 -700);
DISPLAY INVISIBLE (2150 -700);
FORCEPROP 2 LAST BOM_COST VDDQ_KLM_PWR_VR
J 0
(2325 -700);
DISPLAY 1.446809 (2325 -700);
PAINT MONO (2325 -700);
DISPLAY INVISIBLE (2325 -700);
FORCEPROP 1 LAST SIZE 1B
J 0
(2775 -825);
DISPLAY 1.723404 (2775 -825);
PAINT GREEN (2775 -825);
DISPLAY INVISIBLE (2775 -825);
FORCEPROP 1 LAST VOLTAGE 0
J 0
(2700 -775);
PAINT SKYBLUE (2700 -775);
DISPLAY INVISIBLE (2700 -775);
FORCEPROP 2 LAST CDS_LIB mstr_symbols
J 0
(2700 -775);
PAINT ORANGE (2700 -775);
DISPLAY INVISIBLE (2700 -775);
FORCEPROP 1 LAST PATH I70
J 0
(2775 -775);
DISPLAY 1.170213 (2775 -775);
PAINT AQUA (2775 -775);
DISPLAY INVISIBLE (2775 -775);
FORCEPROP 1 LAST BODY_TYPE PLUMBING
J 0
(2655 -818);
DISPLAY 0.340426 (2655 -818);
PAINT GREEN (2655 -818);
DISPLAY INVISIBLE (2655 -818);
FORCEPROP 1 LAST HDL_POWER GND
J 0
(2700 -625);
DISPLAY 1.723404 (2700 -625);
PAINT GREEN (2700 -625);
DISPLAY INVISIBLE (2700 -625);
FORCEADD CAP..1
(-75 250);
FORCEPROP 1 LAST MATERIAL X7R
J 0
(-25 150);
DISPLAY 0.617021 (-25 150);
PAINT SKYBLUE (-25 150);
FORCEPROP 1 LASTPIN (-75 150) $PN 2
J 0
(-65 130);
DISPLAY 0.617021 (-65 130);
PAINT ORANGE (-65 130);
FORCEPROP 1 LASTPIN (-75 350) $PN 1
J 0
(-65 330);
DISPLAY 0.617021 (-65 330);
PAINT ORANGE (-65 330);
FORCEPROP 1 LAST PART_NUMBER A36096-155
J 0
(-25 100);
DISPLAY 0.617021 (-25 100);
PAINT BLUE (-25 100);
FORCEPROP 1 LAST VALUE 0.22UF
J 0
(-25 300);
DISPLAY 0.617021 (-25 300);
PAINT SKYBLUE (-25 300);
FORCEPROP 0 LAST BOM_SS NOPOP
J 0
(100 225);
DISPLAY 0.638298 (100 225);
PAINT BROWN (100 225);
DISPLAY BOTH (100 225);
FORCEPROP 1 LAST VOLTAGE 16V
J 0
(-25 250);
DISPLAY 0.617021 (-25 250);
PAINT SKYBLUE (-25 250);
FORCEPROP 1 LAST TOLERANCE 10%
J 0
(-25 200);
DISPLAY 0.617021 (-25 200);
PAINT SKYBLUE (-25 200);
FORCEPROP 1 LAST PACK_TYPE 0402
J 0
(-25 50);
DISPLAY 0.617021 (-25 50);
PAINT SKYBLUE (-25 50);
FORCEPROP 1 LAST LOCATION C1A13
J 0
(-25 350);
DISPLAY 0.617021 (-25 350);
PAINT AQUA (-25 350);
FORCEPROP 2 LAST SEC 1
J 0
(-25 475);
DISPLAY 0.680851 (-25 475);
PAINT MONO (-25 475);
DISPLAY INVISIBLE (-25 475);
FORCEPROP 2 LAST SEC_TYPE 0402
J 0
(-25 475);
DISPLAY 1.021277 (-25 475);
PAINT ORANGE (-25 475);
DISPLAY INVISIBLE (-25 475);
FORCEPROP 2 LAST ROOM VDDQ_KLM_PWR_VR
J 0
(-25 400);
DISPLAY 1.361702 (-25 400);
PAINT ORANGE (-25 400);
DISPLAY INVISIBLE (-25 400);
FORCEPROP 1 LAST PATH I72
J 0
(-25 400);
DISPLAY 1.319149 (-25 400);
PAINT WHITE (-25 400);
DISPLAY INVISIBLE (-25 400);
FORCEPROP 2 LAST CDS_LOCATION C1A13
J 0
(-25 350);
DISPLAY 0.617021 (-25 350);
PAINT AQUA (-25 350);
DISPLAY INVISIBLE (-25 350);
FORCEPROP 2 LAST CDS_LIB mstr_discrete
J 0
(-75 250);
PAINT ORANGE (-75 250);
DISPLAY INVISIBLE (-75 250);
FORCEADD CAP..1
R 2
(-775 -350);
FORCEPROP 1 LAST LOCATION C1A8
J 2
(-825 -250);
DISPLAY 0.617021 (-825 -250);
PAINT AQUA (-825 -250);
FORCEPROP 0 LAST BOM_SS NOPOP
J 0
(-700 -375);
DISPLAY 0.638298 (-700 -375);
PAINT BROWN (-700 -375);
DISPLAY BOTH (-700 -375);
FORCEPROP 1 LAST PART_NUMBER A36096-104
J 2
(-825 -500);
DISPLAY 0.617021 (-825 -500);
PAINT BLUE (-825 -500);
FORCEPROP 1 LASTPIN (-775 -250) $PN 1
J 2
(-785 -270);
DISPLAY 0.617021 (-785 -270);
PAINT ORANGE (-785 -270);
FORCEPROP 1 LAST VALUE 0.220UF
J 2
(-825 -300);
DISPLAY 0.617021 (-825 -300);
PAINT SKYBLUE (-825 -300);
FORCEPROP 1 LAST VOLTAGE 16V
J 2
(-825 -350);
DISPLAY 0.617021 (-825 -350);
PAINT SKYBLUE (-825 -350);
FORCEPROP 1 LASTPIN (-775 -450) $PN 2
J 2
(-785 -470);
DISPLAY 0.617021 (-785 -470);
PAINT ORANGE (-785 -470);
FORCEPROP 1 LAST PACK_TYPE 0402
J 2
(-825 -550);
DISPLAY 0.617021 (-825 -550);
PAINT SKYBLUE (-825 -550);
FORCEPROP 1 LAST TOLERANCE 10%
J 2
(-825 -400);
DISPLAY 0.617021 (-825 -400);
PAINT SKYBLUE (-825 -400);
FORCEPROP 1 LAST MATERIAL X7R
J 2
(-825 -450);
DISPLAY 0.617021 (-825 -450);
PAINT SKYBLUE (-825 -450);
FORCEPROP 2 LAST CDS_LIB mstr_discrete
J 0
(-775 -350);
PAINT ORANGE (-775 -350);
DISPLAY INVISIBLE (-775 -350);
FORCEPROP 1 LAST PATH I75
J 2
(-825 -200);
DISPLAY 0.978723 (-825 -200);
PAINT WHITE (-825 -200);
DISPLAY INVISIBLE (-825 -200);
FORCEPROP 0 LAST SPOF TRUE
J 0
(-825 -150);
DISPLAY 1.021277 (-825 -150);
PAINT ORANGE (-825 -150);
DISPLAY INVISIBLE (-825 -150);
FORCEPROP 2 LAST SEC 1
J 0
(-825 -150);
DISPLAY 0.680851 (-825 -150);
PAINT MONO (-825 -150);
DISPLAY INVISIBLE (-825 -150);
FORCEPROP 2 LAST CDS_LOCATION C1A8
J 2
(-825 -250);
DISPLAY 0.617021 (-825 -250);
PAINT AQUA (-825 -250);
DISPLAY INVISIBLE (-825 -250);
FORCEPROP 2 LAST SEC_TYPE 0402
J 0
(-825 -150);
DISPLAY 1.021277 (-825 -150);
PAINT ORANGE (-825 -150);
DISPLAY INVISIBLE (-825 -150);
FORCEPROP 2 LAST ROOM VDDQ_KLM_PWR_VR
J 0
(-825 -200);
DISPLAY 1.361702 (-825 -200);
PAINT ORANGE (-825 -200);
DISPLAY INVISIBLE (-825 -200);
FORCEADD CAP..1
(-825 250);
FORCEPROP 1 LAST VOLTAGE 16V
J 0
(-775 250);
DISPLAY 0.617021 (-775 250);
PAINT SKYBLUE (-775 250);
FORCEPROP 1 LASTPIN (-825 150) $PN 2
J 0
(-815 130);
DISPLAY 0.617021 (-815 130);
PAINT ORANGE (-815 130);
FORCEPROP 1 LAST PART_NUMBER D97712-011
J 0
(-775 100);
DISPLAY 0.617021 (-775 100);
PAINT BLUE (-775 100);
FORCEPROP 1 LAST LOCATION C1A6
J 0
(-775 350);
DISPLAY 0.617021 (-775 350);
PAINT AQUA (-775 350);
FORCEPROP 1 LAST VALUE 1.0UF
J 0
(-775 300);
DISPLAY 0.617021 (-775 300);
PAINT SKYBLUE (-775 300);
FORCEPROP 1 LASTPIN (-825 350) $PN 1
J 0
(-815 330);
DISPLAY 0.617021 (-815 330);
PAINT ORANGE (-815 330);
FORCEPROP 0 LAST BOM_SS NOPOP
J 0
(-775 0);
DISPLAY 0.638298 (-775 0);
PAINT BROWN (-775 0);
DISPLAY BOTH (-775 0);
FORCEPROP 1 LAST PACK_TYPE 0402
J 0
(-775 50);
DISPLAY 0.617021 (-775 50);
PAINT SKYBLUE (-775 50);
FORCEPROP 1 LAST MATERIAL X6S
J 0
(-775 150);
DISPLAY 0.617021 (-775 150);
PAINT SKYBLUE (-775 150);
FORCEPROP 1 LAST TOLERANCE 10%
J 0
(-775 200);
DISPLAY 0.617021 (-775 200);
PAINT SKYBLUE (-775 200);
FORCEPROP 2 LAST CDS_LOCATION C1A6
J 0
(-775 350);
DISPLAY 0.617021 (-775 350);
PAINT AQUA (-775 350);
DISPLAY INVISIBLE (-775 350);
FORCEPROP 2 LAST CDS_LIB mstr_discrete
J 0
(-825 250);
PAINT ORANGE (-825 250);
DISPLAY INVISIBLE (-825 250);
FORCEPROP 1 LAST PATH I77
J 0
(-775 400);
DISPLAY 1.319149 (-775 400);
PAINT WHITE (-775 400);
DISPLAY INVISIBLE (-775 400);
FORCEPROP 2 LAST ROOM VDDQ_KLM_PWR_VR
J 0
(-775 400);
DISPLAY 1.361702 (-775 400);
PAINT ORANGE (-775 400);
DISPLAY INVISIBLE (-775 400);
FORCEPROP 2 LAST SEC_TYPE 0402
J 0
(-775 475);
DISPLAY 1.021277 (-775 475);
PAINT ORANGE (-775 475);
DISPLAY INVISIBLE (-775 475);
FORCEPROP 2 LAST SEC 1
J 0
(-775 475);
DISPLAY 0.680851 (-775 475);
PAINT MONO (-775 475);
DISPLAY INVISIBLE (-775 475);
FORCEADD CAP_A..1
(-1075 250);
FORCEPROP 1 LASTPIN (-1075 350) $PN 1
J 0
(-1065 330);
DISPLAY 0.617021 (-1065 330);
PAINT ORANGE (-1065 330);
FORCEPROP 1 LASTPIN (-1075 150) $PN 2
J 0
(-1065 130);
DISPLAY 0.617021 (-1065 130);
PAINT ORANGE (-1065 130);
FORCEPROP 1 LAST TOLERANCE 10%
J 0
(-1025 200);
DISPLAY 0.617021 (-1025 200);
PAINT SKYBLUE (-1025 200);
FORCEPROP 1 LAST VOLTAGE 16V
J 0
(-1025 250);
DISPLAY 0.617021 (-1025 250);
PAINT SKYBLUE (-1025 250);
FORCEPROP 1 LAST LOCATION C1A20
J 0
(-1025 350);
DISPLAY 0.617021 (-1025 350);
PAINT AQUA (-1025 350);
FORCEPROP 1 LAST VALUE 0.1UF
J 0
(-1025 300);
DISPLAY 0.617021 (-1025 300);
PAINT SKYBLUE (-1025 300);
FORCEPROP 1 LAST MATERIAL X7R
J 0
(-1025 150);
DISPLAY 0.617021 (-1025 150);
PAINT SKYBLUE (-1025 150);
FORCEPROP 1 LAST PACK_TYPE 0402V
J 0
(-1025 50);
DISPLAY 0.617021 (-1025 50);
PAINT SKYBLUE (-1025 50);
FORCEPROP 1 LAST PART_NUMBER A36096-030
J 0
(-1025 100);
DISPLAY 0.617021 (-1025 100);
PAINT BLUE (-1025 100);
FORCEPROP 2 LAST CDS_LIB dev_discrete
J 0
(-1075 250);
PAINT ORANGE (-1075 250);
DISPLAY INVISIBLE (-1075 250);
FORCEPROP 1 LAST PATH I78
J 0
(-1025 400);
DISPLAY 0.978723 (-1025 400);
PAINT WHITE (-1025 400);
DISPLAY INVISIBLE (-1025 400);
FORCEPROP 2 LAST CDS_LOCATION C1A20
J 0
(-1025 350);
DISPLAY 0.617021 (-1025 350);
PAINT AQUA (-1025 350);
DISPLAY INVISIBLE (-1025 350);
FORCEPROP 2 LAST CDS_SEC 1
J 0
(-1025 400);
PAINT ORANGE (-1025 400);
DISPLAY INVISIBLE (-1025 400);
FORCEPROP 2 LAST ROOM VDDQ_KLM_PWR_VR
J 0
(-1025 400);
DISPLAY 1.361702 (-1025 400);
PAINT ORANGE (-1025 400);
DISPLAY INVISIBLE (-1025 400);
FORCEPROP 2 LAST SEC_TYPE 0402V
J 0
(-1025 475);
DISPLAY 1.021277 (-1025 475);
PAINT ORANGE (-1025 475);
DISPLAY INVISIBLE (-1025 475);
FORCEPROP 2 LAST SEC 1
J 0
(-1025 475);
DISPLAY 0.680851 (-1025 475);
PAINT MONO (-1025 475);
DISPLAY INVISIBLE (-1025 475);
FORCEADD CAP..1
(-1350 250);
FORCEPROP 1 LASTPIN (-1350 350) $PN 1
J 0
(-1340 330);
DISPLAY 0.617021 (-1340 330);
PAINT ORANGE (-1340 330);
FORCEPROP 1 LAST VOLTAGE 16V
J 0
(-1300 250);
DISPLAY 0.617021 (-1300 250);
PAINT SKYBLUE (-1300 250);
FORCEPROP 1 LAST TOLERANCE 10%
J 0
(-1300 200);
DISPLAY 0.617021 (-1300 200);
PAINT SKYBLUE (-1300 200);
FORCEPROP 1 LAST MATERIAL X6S
J 0
(-1300 150);
DISPLAY 0.617021 (-1300 150);
PAINT SKYBLUE (-1300 150);
FORCEPROP 1 LAST PACK_TYPE 0402
J 0
(-1300 100);
DISPLAY 0.617021 (-1300 100);
PAINT SKYBLUE (-1300 100);
FORCEPROP 1 LASTPIN (-1350 150) $PN 2
J 0
(-1340 130);
DISPLAY 0.617021 (-1340 130);
PAINT ORANGE (-1340 130);
FORCEPROP 1 LAST PART_NUMBER D97712-011
J 0
(-1325 50);
DISPLAY 0.617021 (-1325 50);
PAINT BLUE (-1325 50);
FORCEPROP 1 LAST VALUE 1.0UF
J 0
(-1300 300);
DISPLAY 0.617021 (-1300 300);
PAINT SKYBLUE (-1300 300);
FORCEPROP 1 LAST LOCATION C1A9
J 0
(-1300 350);
DISPLAY 0.617021 (-1300 350);
PAINT AQUA (-1300 350);
FORCEPROP 2 LAST SEC 1
J 0
(-1300 475);
DISPLAY 0.680851 (-1300 475);
PAINT MONO (-1300 475);
DISPLAY INVISIBLE (-1300 475);
FORCEPROP 2 LAST SEC_TYPE 0402
J 0
(-1300 475);
DISPLAY 1.021277 (-1300 475);
PAINT ORANGE (-1300 475);
DISPLAY INVISIBLE (-1300 475);
FORCEPROP 2 LAST ROOM VDDQ_KLM_PWR_VR
J 0
(-1300 400);
DISPLAY 1.361702 (-1300 400);
PAINT ORANGE (-1300 400);
DISPLAY INVISIBLE (-1300 400);
FORCEPROP 1 LAST PATH I79
J 0
(-1300 400);
DISPLAY 1.319149 (-1300 400);
PAINT WHITE (-1300 400);
DISPLAY INVISIBLE (-1300 400);
FORCEPROP 2 LAST CDS_LOCATION C1A9
J 0
(-1300 350);
DISPLAY 0.617021 (-1300 350);
PAINT AQUA (-1300 350);
DISPLAY INVISIBLE (-1300 350);
FORCEPROP 2 LAST CDS_LIB mstr_discrete
J 0
(-1350 250);
PAINT ORANGE (-1350 250);
DISPLAY INVISIBLE (-1350 250);
FORCEADD CAP..1
(-1625 250);
FORCEPROP 1 LAST LOCATION C9L5
J 0
(-1575 350);
DISPLAY 0.617021 (-1575 350);
PAINT AQUA (-1575 350);
FORCEPROP 1 LASTPIN (-1625 150) $PN 2
J 0
(-1615 130);
DISPLAY 0.617021 (-1615 130);
PAINT ORANGE (-1615 130);
FORCEPROP 1 LAST PACK_TYPE 0805
J 0
(-1575 50);
DISPLAY 0.617021 (-1575 50);
PAINT SKYBLUE (-1575 50);
FORCEPROP 1 LAST PART_NUMBER C95333-007
J 0
(-1575 100);
DISPLAY 0.617021 (-1575 100);
PAINT BLUE (-1575 100);
FORCEPROP 1 LASTPIN (-1625 350) $PN 1
J 0
(-1615 330);
DISPLAY 0.617021 (-1615 330);
PAINT ORANGE (-1615 330);
FORCEPROP 1 LAST MATERIAL X6S
J 0
(-1575 150);
DISPLAY 0.617021 (-1575 150);
PAINT SKYBLUE (-1575 150);
FORCEPROP 1 LAST TOLERANCE 10%
J 0
(-1575 200);
DISPLAY 0.617021 (-1575 200);
PAINT SKYBLUE (-1575 200);
FORCEPROP 1 LAST VOLTAGE 16V
J 0
(-1575 250);
DISPLAY 0.617021 (-1575 250);
PAINT SKYBLUE (-1575 250);
FORCEPROP 1 LAST VALUE 10UF
J 0
(-1575 300);
DISPLAY 0.617021 (-1575 300);
PAINT SKYBLUE (-1575 300);
FORCEPROP 2 LAST CDS_LIB mstr_discrete
J 0
(-1625 250);
PAINT ORANGE (-1625 250);
DISPLAY INVISIBLE (-1625 250);
FORCEPROP 1 LAST PATH I80
J 0
(-1575 400);
DISPLAY 1.319149 (-1575 400);
PAINT WHITE (-1575 400);
DISPLAY INVISIBLE (-1575 400);
FORCEPROP 2 LAST CDS_LOCATION C9L5
J 0
(-1575 350);
DISPLAY 0.617021 (-1575 350);
PAINT AQUA (-1575 350);
DISPLAY INVISIBLE (-1575 350);
FORCEPROP 2 LAST ROOM VDDQ_KLM_PWR_VR
J 0
(-1575 400);
DISPLAY 1.361702 (-1575 400);
PAINT ORANGE (-1575 400);
DISPLAY INVISIBLE (-1575 400);
FORCEPROP 2 LAST SEC_TYPE 0805
J 0
(-1575 475);
DISPLAY 1.021277 (-1575 475);
PAINT ORANGE (-1575 475);
DISPLAY INVISIBLE (-1575 475);
FORCEPROP 2 LAST SEC 1
J 0
(-1575 475);
DISPLAY 0.680851 (-1575 475);
PAINT MONO (-1575 475);
DISPLAY INVISIBLE (-1575 475);
FORCEADD CAP..1
(-1900 250);
FORCEPROP 1 LAST PART_NUMBER C95333-007
J 0
(-1850 100);
DISPLAY 0.617021 (-1850 100);
PAINT BLUE (-1850 100);
FORCEPROP 1 LAST MATERIAL X6S
J 0
(-1850 150);
DISPLAY 0.617021 (-1850 150);
PAINT SKYBLUE (-1850 150);
FORCEPROP 1 LAST TOLERANCE 10%
J 0
(-1850 200);
DISPLAY 0.617021 (-1850 200);
PAINT SKYBLUE (-1850 200);
FORCEPROP 1 LAST VOLTAGE 16V
J 0
(-1850 250);
DISPLAY 0.617021 (-1850 250);
PAINT SKYBLUE (-1850 250);
FORCEPROP 1 LAST PACK_TYPE 0805
J 0
(-1850 50);
DISPLAY 0.617021 (-1850 50);
PAINT SKYBLUE (-1850 50);
FORCEPROP 1 LASTPIN (-1900 150) $PN 2
J 0
(-1890 130);
DISPLAY 0.617021 (-1890 130);
PAINT ORANGE (-1890 130);
FORCEPROP 1 LAST VALUE 10UF
J 0
(-1850 300);
DISPLAY 0.617021 (-1850 300);
PAINT SKYBLUE (-1850 300);
FORCEPROP 1 LASTPIN (-1900 350) $PN 1
J 0
(-1890 330);
DISPLAY 0.617021 (-1890 330);
PAINT ORANGE (-1890 330);
FORCEPROP 1 LAST LOCATION C9L13
J 0
(-1850 350);
DISPLAY 0.617021 (-1850 350);
PAINT AQUA (-1850 350);
FORCEPROP 2 LAST CDS_LIB mstr_discrete
J 0
(-1900 250);
PAINT ORANGE (-1900 250);
DISPLAY INVISIBLE (-1900 250);
FORCEPROP 2 LAST ROOM VDDQ_KLM_PWR_VR
J 0
(-1850 400);
DISPLAY 1.361702 (-1850 400);
PAINT ORANGE (-1850 400);
DISPLAY INVISIBLE (-1850 400);
FORCEPROP 1 LAST PATH I81
J 0
(-1850 400);
DISPLAY 1.319149 (-1850 400);
PAINT WHITE (-1850 400);
DISPLAY INVISIBLE (-1850 400);
FORCEPROP 2 LAST CDS_LOCATION C9L13
J 0
(-1850 350);
DISPLAY 0.617021 (-1850 350);
PAINT AQUA (-1850 350);
DISPLAY INVISIBLE (-1850 350);
FORCEPROP 2 LAST SEC 1
J 0
(-1850 475);
DISPLAY 0.680851 (-1850 475);
PAINT MONO (-1850 475);
DISPLAY INVISIBLE (-1850 475);
FORCEPROP 2 LAST SEC_TYPE 0805
J 0
(-1850 475);
DISPLAY 1.021277 (-1850 475);
PAINT ORANGE (-1850 475);
DISPLAY INVISIBLE (-1850 475);
FORCEADD OFFPAGE..1
(650 -125);
FORCEPROP 2 LAST $XR0 226 
J 0
(398 -125);
DISPLAY 0.638298 (398 -125);
PAINT MONO (398 -125);
FORCEPROP 2 LAST ROOM VDDQ_KLM_PWR_VR
J 0
(250 -50);
DISPLAY 1.936170 (250 -50);
PAINT ORANGE (250 -50);
DISPLAY INVISIBLE (250 -50);
FORCEPROP 2 LAST BOM_COST VDDQ_KLM_PWR_VR
J 0
(400 -75);
DISPLAY 1.446809 (400 -75);
PAINT MONO (400 -75);
DISPLAY INVISIBLE (400 -75);
FORCEPROP 2 LAST CDS_LIB mstr_standard
J 0
(650 -125);
PAINT ORANGE (650 -125);
DISPLAY INVISIBLE (650 -125);
FORCEPROP 2 LAST PATH I82
J 0
(705 -50);
DISPLAY 1.361702 (705 -50);
PAINT ORANGE (705 -50);
DISPLAY INVISIBLE (705 -50);
FORCEPROP 1 LAST OFFPAGE TRUE
J 0
(975 -250);
DISPLAY 1.680851 (975 -250);
PAINT GREEN (975 -250);
DISPLAY INVISIBLE (975 -250);
FORCEPROP 1 LAST COMMENT_BODY TRUE
J 0
(775 -225);
DISPLAY 1.680851 (775 -225);
PAINT GREEN (775 -225);
DISPLAY INVISIBLE (775 -225);
FORCEADD VCC_CORE..1
(-2175 550);
FORCEPROP 3 LASTPIN (-2175 500) SIG_NAME VR_FET_SW_P12V_STBY_PVDDQ_KLM\g
J 0
(-2165 510);
DISPLAY 0.659574 (-2165 510);
PAINT MONO (-2165 510);
DISPLAY INVISIBLE (-2165 510);
FORCEPROP 1 LAST HDL_POWER VR_FET_SW_P12V_STBY_PVDDQ_KLM
J 1
(-2050 600);
DISPLAY 0.617021 (-2050 600);
PAINT GREEN (-2050 600);
FORCEPROP 2 LAST CDS_LIB mstr_symbols
J 0
(-2175 550);
PAINT ORANGE (-2175 550);
DISPLAY INVISIBLE (-2175 550);
FORCEPROP 1 LAST PATH I83
J 0
(-2125 575);
DISPLAY 1.170213 (-2125 575);
PAINT AQUA (-2125 575);
DISPLAY INVISIBLE (-2125 575);
FORCEADD CAP..1
(-2175 250);
FORCEPROP 1 LAST TOLERANCE 10%
J 0
(-2125 200);
DISPLAY 0.617021 (-2125 200);
PAINT SKYBLUE (-2125 200);
FORCEPROP 1 LAST VOLTAGE 16V
J 0
(-2125 250);
DISPLAY 0.617021 (-2125 250);
PAINT SKYBLUE (-2125 250);
FORCEPROP 1 LAST VALUE 10UF
J 0
(-2125 300);
DISPLAY 0.617021 (-2125 300);
PAINT SKYBLUE (-2125 300);
FORCEPROP 1 LASTPIN (-2175 350) $PN 1
J 0
(-2165 330);
DISPLAY 0.617021 (-2165 330);
PAINT ORANGE (-2165 330);
FORCEPROP 1 LAST PART_NUMBER C95333-007
J 0
(-2125 100);
DISPLAY 0.617021 (-2125 100);
PAINT BLUE (-2125 100);
FORCEPROP 1 LAST MATERIAL X6S
J 0
(-2125 150);
DISPLAY 0.617021 (-2125 150);
PAINT SKYBLUE (-2125 150);
FORCEPROP 1 LAST PACK_TYPE 0805
J 0
(-2125 50);
DISPLAY 0.617021 (-2125 50);
PAINT SKYBLUE (-2125 50);
FORCEPROP 1 LASTPIN (-2175 150) $PN 2
J 0
(-2165 130);
DISPLAY 0.617021 (-2165 130);
PAINT ORANGE (-2165 130);
FORCEPROP 1 LAST LOCATION C9L14
J 0
(-2125 350);
DISPLAY 0.617021 (-2125 350);
PAINT AQUA (-2125 350);
FORCEPROP 2 LAST CDS_LIB mstr_discrete
J 0
(-2175 250);
PAINT ORANGE (-2175 250);
DISPLAY INVISIBLE (-2175 250);
FORCEPROP 2 LAST CDS_LOCATION C9L14
J 0
(-2125 350);
DISPLAY 0.617021 (-2125 350);
PAINT AQUA (-2125 350);
DISPLAY INVISIBLE (-2125 350);
FORCEPROP 1 LAST PATH I84
J 0
(-2125 400);
DISPLAY 1.319149 (-2125 400);
PAINT WHITE (-2125 400);
DISPLAY INVISIBLE (-2125 400);
FORCEPROP 2 LAST ROOM VDDQ_KLM_PWR_VR
J 0
(-2125 400);
DISPLAY 1.361702 (-2125 400);
PAINT ORANGE (-2125 400);
DISPLAY INVISIBLE (-2125 400);
FORCEPROP 2 LAST SEC_TYPE 0805
J 0
(-2125 475);
DISPLAY 1.021277 (-2125 475);
PAINT ORANGE (-2125 475);
DISPLAY INVISIBLE (-2125 475);
FORCEPROP 2 LAST SEC 1
J 0
(-2125 475);
DISPLAY 0.680851 (-2125 475);
PAINT MONO (-2125 475);
DISPLAY INVISIBLE (-2125 475);
FORCEADD GND..1
(-2175 -150);
FORCEPROP 3 LASTPIN (-2175 -100) SIG_NAME GND\g
J 0
(-2165 -90);
DISPLAY 0.659574 (-2165 -90);
PAINT MONO (-2165 -90);
DISPLAY INVISIBLE (-2165 -90);
FORCEPROP 1 LAST HDL_POWER GND
J 0
(-2175 0);
DISPLAY 1.723404 (-2175 0);
PAINT GREEN (-2175 0);
DISPLAY INVISIBLE (-2175 0);
FORCEPROP 1 LAST BODY_TYPE PLUMBING
J 0
(-2220 -193);
DISPLAY 0.340426 (-2220 -193);
PAINT GREEN (-2220 -193);
DISPLAY INVISIBLE (-2220 -193);
FORCEPROP 1 LAST SIZE 1B
J 0
(-2100 -200);
DISPLAY 1.723404 (-2100 -200);
PAINT GREEN (-2100 -200);
DISPLAY INVISIBLE (-2100 -200);
FORCEPROP 1 LAST PATH I85
J 0
(-2100 -150);
DISPLAY 1.170213 (-2100 -150);
PAINT AQUA (-2100 -150);
DISPLAY INVISIBLE (-2100 -150);
FORCEPROP 2 LAST CDS_LIB mstr_symbols
J 0
(-2175 -150);
PAINT ORANGE (-2175 -150);
DISPLAY INVISIBLE (-2175 -150);
FORCEPROP 1 LAST VOLTAGE 0
J 0
(-2175 -150);
PAINT SKYBLUE (-2175 -150);
DISPLAY INVISIBLE (-2175 -150);
FORCEPROP 2 LAST BOM_COST VDDQ_KLM_PWR_VR
J 0
(-2550 -75);
DISPLAY 1.446809 (-2550 -75);
PAINT MONO (-2550 -75);
DISPLAY INVISIBLE (-2550 -75);
FORCEPROP 2 LAST ROOM VDDQ_KLM_PWR_VR
J 0
(-2725 -75);
DISPLAY 1.936170 (-2725 -75);
PAINT ORANGE (-2725 -75);
DISPLAY INVISIBLE (-2725 -75);
FORCEADD VCC_CORE..1
(-1850 2850);
FORCEPROP 3 LASTPIN (-1850 2800) SIG_NAME VR_FET_SW_P12V_STBY_PVDDQ_KLM\g
J 0
(-1840 2810);
DISPLAY 0.659574 (-1840 2810);
PAINT MONO (-1840 2810);
DISPLAY INVISIBLE (-1840 2810);
FORCEPROP 1 LAST HDL_POWER VR_FET_SW_P12V_STBY_PVDDQ_KLM
J 1
(-1775 2900);
DISPLAY 0.617021 (-1775 2900);
PAINT GREEN (-1775 2900);
FORCEPROP 2 LAST CDS_LIB mstr_symbols
J 0
(-1850 2850);
PAINT ORANGE (-1850 2850);
DISPLAY INVISIBLE (-1850 2850);
FORCEPROP 1 LAST PATH I86
J 0
(-1800 2875);
DISPLAY 1.170213 (-1800 2875);
PAINT AQUA (-1800 2875);
DISPLAY INVISIBLE (-1800 2875);
FORCEADD P5V_STBY..1
(550 925);
FORCEPROP 3 LASTPIN (550 875) SIG_NAME P5V_STBY\g
J 0
(560 885);
DISPLAY 0.659574 (560 885);
PAINT MONO (560 885);
DISPLAY INVISIBLE (560 885);
FORCEPROP 1 LAST VOLTAGE 5.0V
J 0
(505 882);
DISPLAY 0.340426 (505 882);
PAINT SKYBLUE (505 882);
DISPLAY INVISIBLE (505 882);
FORCEPROP 2 LAST CDS_LIB mstr_symbols
J 0
(550 925);
PAINT ORANGE (550 925);
DISPLAY INVISIBLE (550 925);
FORCEPROP 1 LAST SIZE 1B
J 0
(595 947);
DISPLAY 0.340426 (595 947);
PAINT GREEN (595 947);
DISPLAY INVISIBLE (595 947);
FORCEPROP 1 LAST PATH I88
J 0
(595 927);
DISPLAY 0.340426 (595 927);
PAINT GREEN (595 927);
DISPLAY INVISIBLE (595 927);
FORCEPROP 1 LAST BODY_TYPE PLUMBING
J 0
(505 882);
DISPLAY 0.340426 (505 882);
PAINT GREEN (505 882);
DISPLAY INVISIBLE (505 882);
FORCEPROP 1 LAST HDL_POWER P5V_STBY
J 0
(250 800);
DISPLAY 0.872340 (250 800);
PAINT ORANGE (250 800);
DISPLAY INVISIBLE (250 800);
FORCEADD INTEL_CORP_BPAGE..1
(5425 -1550);
FORCEPROP 1 LAST CDS_CON_LAST_MODIFIED Fri Jun 16 17:49:21 2017
J 0
(4000 -1225);
DISPLAY 1.936170 (4000 -1225);
PAINT GREEN (4000 -1225);
DISPLAY INVISIBLE (4000 -1225);
FORCEPROP 2 LAST CUSTOM_TXT_CDS <XR_PAGE_TITLE>
J 0
(-2465 3700);
DISPLAY 0.638298 (-2465 3700);
PAINT PINK (-2465 3700);
DISPLAY INVISIBLE (-2465 3700);
FORCEPROP 2 LAST CUSTOM_TXT_CDS <CON_LAST_MODIFIED>
J 0
(1425 -1450);
PAINT ORANGE (1425 -1450);
FORCEPROP 2 LAST CUSTOM_TXT_CDS <CURRENT_DESIGN_SHEET> OF <TOTAL_DESIGN_SHEETS>
J 0
(4925 -1525);
PAINT ORANGE (4925 -1525);
FORCEPROP 1 LAST SCH_TITLE VDDQ KLM VR (2 OF 3)
J 0
(-2525 -1500);
DISPLAY 1.212766 (-2525 -1500);
PAINT ORANGE (-2525 -1500);
FORCEPROP 1 LAST COMMENT_BODY TRUE
J 0
(5437 -1538);
DISPLAY 0.893617 (5437 -1538);
PAINT GREEN (5437 -1538);
DISPLAY INVISIBLE (5437 -1538);
FORCEPROP 2 LAST CDS_LIB mstr_symbols
J 0
(5425 -1550);
DISPLAY 1.936170 (5425 -1550);
PAINT ORANGE (5425 -1550);
DISPLAY INVISIBLE (5425 -1550);
FORCEPROP 2 LAST PAGE_BORDER TRUE
J 0
(-2465 3700);
DISPLAY 1.255319 (-2465 3700);
PAINT PINK (-2465 3700);
DISPLAY INVISIBLE (-2465 3700);
FORCEPROP 2 LAST ROOM VDDQ_KLM_PWR_VR
J 0
(-2675 3550);
DISPLAY 1.936170 (-2675 3550);
PAINT ORANGE (-2675 3550);
DISPLAY INVISIBLE (-2675 3550);
FORCEPROP 2 LAST CDS_XR_PAGE_TITLE CR-227 : @BASEBOARD_FAB2_LIB.BASEBOARD_FAB2(SCH_1):PAGE227
J 0
(-2465 3700);
DISPLAY 0.638298 (-2465 3700);
PAINT PINK (-2465 3700);
DISPLAY INVISIBLE (-2465 3700);
FORCEADD DNS..2
(4655 2395);
PAINT RED (4655 2395);
FORCEPROP 1 LAST COMMENT_BODY TRUE
R 1
J 0
(4730 2170);
DISPLAY 0.872340 (4730 2170);
PAINT GREEN (4730 2170);
DISPLAY INVISIBLE (4730 2170);
FORCEPROP 2 LAST CDS_LIB mstr_misc
J 0
(4655 2395);
PAINT ORANGE (4655 2395);
DISPLAY INVISIBLE (4655 2395);
FORCEADD DNS..2
(4655 145);
PAINT RED (4655 145);
FORCEPROP 2 LAST CDS_LIB mstr_misc
J 0
(4655 145);
PAINT ORANGE (4655 145);
DISPLAY INVISIBLE (4655 145);
FORCEPROP 1 LAST COMMENT_BODY TRUE
R 1
J 0
(4730 -80);
DISPLAY 0.872340 (4730 -80);
PAINT GREEN (4730 -80);
DISPLAY INVISIBLE (4730 -80);
WIRE 16 -1 (4350 1925)(4350 1975);
WIRE 16 -1 (4100 1925)(4350 1925);
WIRE 16 -1 (4350 1875)(4350 1925);
WIRE 16 -1 (4100 1075)(4100 1925);
WIRE 16 -1 (3925 1925)(4100 1925);
WIRE 16 -1 (1250 1075)(4100 1075);
WIRE 16 -1 (1250 2375)(1250 1075);
WIRE 16 -1 (1325 2375)(1250 2375);
WIRE 16 -1 (4650 2250)(4650 2300);
WIRE 16 -1 (4650 25)(4650 50);
WIRE 16 -1 (600 3100)(600 3150);
WIRE 16 -1 (600 2575)(600 3100);
WIRE 16 -1 (-100 3100)(600 3100);
WIRE 16 -1 (-100 3100)(-475 3100);
WIRE 16 -1 (-100 2575)(-100 3100);
WIRE 16 -1 (1200 2575)(600 2575);
WIRE 16 -1 (1200 2475)(1200 2575);
WIRE 16 -1 (1325 2575)(1200 2575);
WIRE 16 -1 (-650 3100)(-475 3100);
WIRE 16 -1 (-475 2550)(-475 3100);
WIRE 16 -1 (1325 2475)(1200 2475);
WIRE 16 -1 (1150 1625)(1150 1525);
WIRE 16 -1 (2825 1200)(2825 1175);
WIRE 16 -1 (3050 2100)(3050 2050);
WIRE 16 -1 (2925 -950)(2925 -925);
WIRE 16 -1 (2950 -75)(2950 -125);
WIRE 16 -1 (1150 -900)(1150 -950);
WIRE 16 -1 (2675 1525)(2675 1675);
WIRE 16 -1 (2675 1675)(2675 1725);
WIRE 16 -1 (2675 1675)(2325 1675);
WIRE 16 -1 (2675 1725)(2675 1775);
WIRE 16 -1 (2675 1725)(2325 1725);
WIRE 16 -1 (2675 1775)(2675 1825);
WIRE 16 -1 (2675 1775)(2325 1775);
WIRE 16 -1 (2325 1825)(2675 1825);
WIRE 16 -1 (-2250 2175)(-2250 2200);
WIRE 16 -1 (-1975 2200)(-2250 2200);
WIRE 16 -1 (-2250 2400)(-2250 2200);
WIRE 16 -1 (-1975 2200)(-1700 2200);
WIRE 16 -1 (-1975 2400)(-1975 2200);
WIRE 16 -1 (-1700 2200)(-1425 2200);
WIRE 16 -1 (-1700 2400)(-1700 2200);
WIRE 16 -1 (-1425 2200)(-1175 2200);
WIRE 16 -1 (-1425 2375)(-1425 2200);
WIRE 16 -1 (-1175 2200)(-900 2200);
WIRE 16 -1 (-1175 2375)(-1175 2200);
WIRE 16 -1 (-900 2200)(-475 2200);
WIRE 16 -1 (-900 2400)(-900 2200);
WIRE 16 -1 (-100 2200)(-475 2200);
WIRE 16 -1 (-475 2400)(-475 2200);
WIRE 16 -1 (-100 2375)(-100 2200);
WIRE 16 -1 (4375 -325)(4375 -275);
WIRE 16 -1 (4375 -325)(4300 -325);
WIRE 16 -1 (4375 -375)(4375 -325);
WIRE 16 -1 (4300 -1050)(4300 -325);
WIRE 16 -1 (3925 -325)(4300 -325);
WIRE 16 -1 (1200 -1050)(4300 -1050);
WIRE 16 -1 (1200 125)(1200 -1050);
WIRE 16 -1 (1325 125)(1200 125);
WIRE 16 -1 (4375 -600)(4375 -575);
WIRE 16 -1 (4350 1650)(4350 1675);
WIRE 16 -1 (2700 -725)(2700 -575);
WIRE 16 -1 (2700 -575)(2700 -525);
WIRE 16 -1 (2700 -575)(2325 -575);
WIRE 16 -1 (2700 -525)(2700 -475);
WIRE 16 -1 (2700 -525)(2325 -525);
WIRE 16 -1 (2700 -475)(2700 -425);
WIRE 16 -1 (2700 -475)(2325 -475);
WIRE 16 -1 (2325 -425)(2700 -425);
WIRE 16 -1 (-2175 500)(-2175 425);
WIRE 16 -1 (-2175 425)(-1900 425);
WIRE 16 -1 (-2175 350)(-2175 425);
WIRE 16 -1 (-1625 425)(-1900 425);
WIRE 16 -1 (-1900 350)(-1900 425);
WIRE 16 -1 (-1625 425)(-1350 425);
WIRE 16 -1 (-1625 350)(-1625 425);
WIRE 16 -1 (-1075 425)(-1350 425);
WIRE 16 -1 (-1350 350)(-1350 425);
WIRE 16 -1 (1100 425)(-1075 425);
WIRE 16 -1 (-1075 350)(-1075 425);
WIRE 16 -1 (1100 475)(1100 425);
WIRE 16 -1 (1325 425)(1100 425);
WIRE 16 -1 (1100 475)(1325 475);
WIRE 16 -1 (-2175 -100)(-2175 -75);
WIRE 16 -1 (-1900 -75)(-2175 -75);
WIRE 16 -1 (-2175 150)(-2175 -75);
WIRE 16 -1 (-1625 -75)(-1900 -75);
WIRE 16 -1 (-1900 150)(-1900 -75);
WIRE 16 -1 (-1625 -75)(-1350 -75);
WIRE 16 -1 (-1625 150)(-1625 -75);
WIRE 16 -1 (-1075 -75)(-1350 -75);
WIRE 16 -1 (-1350 150)(-1350 -75);
WIRE 16 -1 (-1075 -75)(-825 -75);
WIRE 16 -1 (-1075 150)(-1075 -75);
WIRE 16 -1 (-825 -75)(-425 -75);
WIRE 16 -1 (-825 150)(-825 -75);
WIRE 16 -1 (-75 -75)(-425 -75);
WIRE 16 -1 (-425 150)(-425 -75);
WIRE 16 -1 (-75 150)(-75 -75);
WIRE 16 -1 (-1850 2800)(-1850 2675);
WIRE 16 -1 (-1850 2675)(-1700 2675);
WIRE 16 -1 (-1850 2675)(-1975 2675);
WIRE 16 -1 (-2250 2675)(-1975 2675);
WIRE 16 -1 (-1975 2600)(-1975 2675);
WIRE 16 -1 (-1700 2675)(-1425 2675);
WIRE 16 -1 (-1700 2600)(-1700 2675);
WIRE 16 -1 (-1425 2675)(-1175 2675);
WIRE 16 -1 (-1425 2575)(-1425 2675);
WIRE 16 -1 (-2250 2600)(-2250 2675);
WIRE 16 -1 (1075 2675)(-1175 2675);
WIRE 16 -1 (-1175 2575)(-1175 2675);
WIRE 16 -1 (1075 2725)(1075 2675);
WIRE 16 -1 (1325 2675)(1075 2675);
WIRE 16 -1 (1325 2725)(1075 2725);
WIRE 16 -1 (550 800)(550 875);
WIRE 16 -1 (550 800)(550 325);
WIRE 16 -1 (550 800)(-75 800);
WIRE 16 -1 (-75 800)(-425 800);
WIRE 16 -1 (-75 350)(-75 800);
WIRE 16 -1 (550 325)(1225 325);
WIRE 16 -1 (1225 225)(1225 325);
WIRE 16 -1 (1225 325)(1325 325);
WIRE 16 -1 (-575 800)(-425 800);
WIRE 16 -1 (-425 300)(-425 800);
WIRE 16 -1 (1325 225)(1225 225);
WIRE 3 682 (-2250 400)(-900 400);
WIRE 3 682 (-2250 0)(-2250 400);
WIRE 3 682 (-900 400)(-900 0);
WIRE 3 682 (-900 0)(-2250 0);
WIRE 16 2175 (-525 -50)(225 -50);
WIRE 16 2175 (225 400)(225 -50);
WIRE 16 2175 (-525 400)(-525 -50);
WIRE 16 2175 (-525 400)(225 400);
WIRE 16 2175 (-1075 -575)(-25 -575);
WIRE 16 2175 (-25 -175)(-25 -575);
WIRE 16 2175 (-1075 -175)(-1075 -575);
WIRE 16 2175 (-1075 -175)(-25 -175);
WIRE 3 682 (-375 75)(-475 75);
WIRE 3 682 (-375 350)(-375 75);
WIRE 3 682 (-475 75)(-475 350);
WIRE 3 682 (-475 350)(-375 350);
WIRE 16 -1 (-825 800)(-775 800);
WIRE 16 -1 (-825 525)(-825 800);
WIRE 16 -1 (-825 525)(1325 525);
FORCEPROP 2 LAST SIG_NAME VR_PVDDQ_KLM_PH2_VCIN
J 0
(-765 535);
DISPLAY 0.617021 (-765 535);
PAINT ORANGE (-765 535);
FORCEPROP 2 LASTPROP $XRERR UNIQUE?
J 0
(-1005 535);
DISPLAY 0.638298 (-1005 535);
PAINT MONO (-1005 535);
DISPLAY INVISIBLE (-1005 535);
WIRE 16 -1 (-825 350)(-825 525);
WIRE 3 2175 (0 -150)(0 -350);
WIRE 3 2175 (0 -350)(425 -350);
WIRE 3 2175 (0 -150)(425 -150);
WIRE 3 2175 (425 -150)(425 -350);
WIRE 16 -1 (700 -125)(1325 -125);
FORCEPROP 2 LAST SIG_NAME VR_PVDDQ_KLM_PWM2
J 0
(687 -115);
DISPLAY 0.617021 (687 -115);
PAINT ORANGE (687 -115);
WIRE 3 682 (-2400 1000)(-2400 -1150);
WIRE 3 682 (5200 1000)(-2400 1000);
WIRE 3 682 (-2400 -1150)(5200 -1150);
WIRE 3 682 (5200 -1150)(5200 1000);
WIRE 16 -1 (1025 1875)(1325 1875);
WIRE 16 -1 (1025 1775)(1025 1875);
WIRE 16 -1 (-825 1775)(-825 1825);
WIRE 16 -1 (-825 1775)(1025 1775);
FORCEPROP 2 LAST SIG_NAME VR_PVDDQ_KLM_PH1_PHASE
J 0
(-640 1785);
DISPLAY 0.617021 (-640 1785);
PAINT ORANGE (-640 1785);
FORCEPROP 2 LASTPROP $XRERR UNIQUE?
J 0
(-880 1785);
DISPLAY 0.638298 (-880 1785);
PAINT MONO (-880 1785);
DISPLAY INVISIBLE (-880 1785);
WIRE 16 2175 (-1150 1700)(-700 1700);
WIRE 16 2175 (-700 2100)(-700 1700);
WIRE 16 2175 (-1150 2100)(-1150 1700);
WIRE 16 2175 (-1150 2100)(-700 2100);
WIRE 16 -1 (-1425 2125)(1325 2125);
WIRE 16 -1 (-900 3100)(-850 3100);
WIRE 16 -1 (-900 2600)(-900 2775);
WIRE 16 -1 (-900 2775)(-900 3100);
FORCEPROP 2 LAST SIG_NAME VR_PVDDQ_KLM_PH1_VCIN
J 0
(-890 2785);
DISPLAY 0.617021 (-890 2785);
PAINT ORANGE (-890 2785);
FORCEPROP 2 LASTPROP $XRERR UNIQUE?
J 0
(-1130 2785);
DISPLAY 0.638298 (-1130 2785);
PAINT MONO (-1130 2785);
DISPLAY INVISIBLE (-1130 2785);
WIRE 16 -1 (1325 2775)(-900 2775);
WIRE 16 -1 (1150 -700)(1150 -225);
WIRE 16 -1 (1325 -225)(1150 -225);
WIRE 16 -1 (1150 -225)(1150 875);
WIRE 16 -1 (1150 875)(3925 875);
FORCEPROP 2 LAST SIG_NAME VR_PVDDQ_KLM_AIREF2
J 0
(3072 876);
DISPLAY 0.617021 (3072 876);
PAINT ORANGE (3072 876);
WIRE 3 2175 (-100 2100)(500 2100);
WIRE 3 2175 (500 2100)(500 1850);
WIRE 3 2175 (-100 2100)(-100 1850);
WIRE 3 2175 (-100 1850)(500 1850);
WIRE 3 2175 (2675 -225)(3275 -225);
WIRE 3 2175 (3275 150)(3275 -225);
WIRE 3 2175 (2675 150)(2675 -225);
WIRE 3 2175 (2675 150)(3275 150);
WIRE 16 -1 (350 -25)(1325 -25);
FORCEPROP 0 LAST SIG_NAME TP_PVDDQ_KLM_PH2_GL_0
J 0
(377 -10);
DISPLAY 0.617021 (377 -10);
PAINT ORANGE (377 -10);
FORCEPROP 2 LASTPROP $XRERR UNIQUE?
J 0
(110 -25);
DISPLAY 0.638298 (110 -25);
PAINT MONO (110 -25);
DISPLAY INVISIBLE (110 -25);
WIRE 16 -1 (350 25)(1325 25);
FORCEPROP 0 LAST SIG_NAME TP_PVDDQ_KLM_PH2_GL_1
J 0
(377 40);
DISPLAY 0.617021 (377 40);
PAINT ORANGE (377 40);
FORCEPROP 2 LASTPROP $XRERR UNIQUE?
J 0
(110 25);
DISPLAY 0.638298 (110 25);
PAINT MONO (110 25);
DISPLAY INVISIBLE (110 25);
WIRE 16 -1 (1050 -325)(1325 -325);
WIRE 16 -1 (1050 -250)(1050 -325);
WIRE 16 -1 (325 -250)(1050 -250);
FORCEPROP 2 LAST SIG_NAME VR_PVDDQ_KLM_PH2_BOOT_R
J 0
(485 -240);
DISPLAY 0.617021 (485 -240);
PAINT ORANGE (485 -240);
FORCEPROP 2 LASTPROP $XRERR UNIQUE?
J 0
(245 -240);
DISPLAY 0.638298 (245 -240);
PAINT MONO (245 -240);
DISPLAY INVISIBLE (245 -240);
WIRE 16 -1 (1050 -375)(1325 -375);
WIRE 16 -1 (1050 -475)(1050 -375);
WIRE 16 -1 (-775 -475)(-775 -450);
WIRE 16 -1 (-775 -475)(1050 -475);
FORCEPROP 2 LAST SIG_NAME VR_PVDDQ_KLM_PH2_PHASE
J 0
(-740 -465);
DISPLAY 0.617021 (-740 -465);
PAINT ORANGE (-740 -465);
FORCEPROP 2 LASTPROP $XRERR UNIQUE?
J 0
(-980 -465);
DISPLAY 0.638298 (-980 -465);
PAINT MONO (-980 -465);
DISPLAY INVISIBLE (-980 -465);
WIRE 16 -1 (2925 -375)(2925 -325);
WIRE 16 -1 (2925 -325)(3625 -325);
WIRE 16 -1 (2325 -325)(2925 -325);
FORCEPROP 2 LAST SIG_NAME VR_PVDDQ_KLM_PH2_SW
J 0
(2410 -315);
DISPLAY 0.617021 (2410 -315);
PAINT ORANGE (2410 -315);
FORCEPROP 2 LASTPROP $XRERR UNIQUE?
J 0
(2170 -315);
DISPLAY 0.638298 (2170 -315);
PAINT MONO (2170 -315);
DISPLAY INVISIBLE (2170 -315);
WIRE 16 -1 (2325 525)(3900 525);
FORCEPROP 2 LAST SIG_NAME ISENSE_PVDDQ_KLM_PH2_IMON
J 0
(2887 535);
DISPLAY 0.617021 (2887 535);
PAINT ORANGE (2887 535);
WIRE 16 -1 (4650 250)(4650 325);
WIRE 16 -1 (2325 325)(4650 325);
FORCEPROP 0 LAST VOLTAGE 3.6
J 0
(2400 400);
DISPLAY 1.021277 (2400 400);
PAINT SKYBLUE (2400 400);
DISPLAY INVISIBLE (2400 400);
FORCEPROP 2 LAST SIG_NAME VR_PVDDQ_KLM_PH2_OCSET
J 0
(2457 341);
DISPLAY 0.617021 (2457 341);
PAINT ORANGE (2457 341);
FORCEPROP 2 LASTPROP $XRERR UNIQUE?
J 0
(2217 341);
DISPLAY 0.638298 (2217 341);
PAINT MONO (2217 341);
DISPLAY INVISIBLE (2217 341);
WIRE 3 2175 (2850 -1025)(3525 -1025);
WIRE 3 2175 (3525 -275)(3525 -1025);
WIRE 3 2175 (2850 -275)(2850 -1025);
WIRE 3 2175 (2850 -275)(3525 -275);
WIRE 16 -1 (2925 -575)(2925 -625);
WIRE 16 -1 (2925 -675)(2925 -625);
WIRE 16 -1 (3450 -625)(2925 -625);
FORCEPROP 2 LAST SIG_NAME VR_PVDDQ_KLM_PH2_RC
J 0
(2960 -615);
DISPLAY 0.617021 (2960 -615);
PAINT ORANGE (2960 -615);
FORCEPROP 2 LASTPROP $XRERR UNIQUE?
J 0
(3480 -625);
DISPLAY 0.638298 (3480 -625);
PAINT MONO (3480 -625);
DISPLAY INVISIBLE (3480 -625);
WIRE 16 -1 (2950 125)(2950 175);
WIRE 16 -1 (2950 175)(3425 175);
WIRE 16 -1 (2325 175)(2325 25);
WIRE 16 -1 (2325 175)(2950 175);
FORCEPROP 2 LAST SIG_NAME A_TSENSE_PVDDQ_KLM
J 0
(2587 185);
DISPLAY 0.617021 (2587 185);
PAINT ORANGE (2587 185);
WIRE 16 -1 (-775 -250)(125 -250);
FORCEPROP 2 LAST SIG_NAME VR_PVDDQ_KLM_PH2_BOOT
J 0
(-740 -240);
DISPLAY 0.617021 (-740 -240);
PAINT ORANGE (-740 -240);
FORCEPROP 2 LASTPROP $XRERR UNIQUE?
J 0
(-980 -240);
DISPLAY 0.638298 (-980 -240);
PAINT MONO (-980 -240);
DISPLAY INVISIBLE (-980 -240);
WIRE 3 682 (2375 275)(2475 275);
WIRE 16 -1 (4650 2500)(4650 2575);
WIRE 16 -1 (2325 2575)(4650 2575);
FORCEPROP 0 LAST VOLTAGE 3.6
J 0
(2400 2650);
DISPLAY 1.021277 (2400 2650);
PAINT SKYBLUE (2400 2650);
DISPLAY INVISIBLE (2400 2650);
FORCEPROP 2 LAST SIG_NAME VR_PVDDQ_KLM_PH1_OCSET
J 0
(2457 2591);
DISPLAY 0.617021 (2457 2591);
PAINT ORANGE (2457 2591);
FORCEPROP 2 LASTPROP $XRERR UNIQUE?
J 0
(2217 2591);
DISPLAY 0.638298 (2217 2591);
PAINT MONO (2217 2591);
DISPLAY INVISIBLE (2217 2591);
WIRE 3 2175 (2750 1100)(3300 1100);
WIRE 3 2175 (3300 1900)(3300 1100);
WIRE 3 2175 (2750 1900)(2750 1100);
WIRE 3 2175 (2750 1900)(3300 1900);
WIRE 16 -1 (2825 1650)(2825 1525);
WIRE 16 -1 (2825 1525)(3275 1525);
FORCEPROP 2 LAST SIG_NAME VR_PVDDQ_KLM_PH1_RC
J 0
(2835 1535);
DISPLAY 0.617021 (2835 1535);
PAINT ORANGE (2835 1535);
FORCEPROP 2 LASTPROP $XRERR UNIQUE?
J 0
(3305 1525);
DISPLAY 0.638298 (3305 1525);
PAINT MONO (3305 1525);
DISPLAY INVISIBLE (3305 1525);
WIRE 16 -1 (2825 1450)(2825 1525);
WIRE 16 -1 (-825 2025)(0 2025);
FORCEPROP 2 LAST SIG_NAME VR_PVDDQ_KLM_PH1_BOOT
J 0
(-640 2035);
DISPLAY 0.617021 (-640 2035);
PAINT ORANGE (-640 2035);
FORCEPROP 2 LASTPROP $XRERR UNIQUE?
J 0
(-880 2035);
DISPLAY 0.638298 (-880 2035);
PAINT MONO (-880 2035);
DISPLAY INVISIBLE (-880 2035);
WIRE 16 -1 (425 2225)(1325 2225);
FORCEPROP 0 LAST SIG_NAME TP_PVDDQ_KLM_PH1_GL_0
J 0
(502 2240);
DISPLAY 0.617021 (502 2240);
PAINT ORANGE (502 2240);
FORCEPROP 2 LASTPROP $XRERR UNIQUE?
J 0
(185 2225);
DISPLAY 0.638298 (185 2225);
PAINT MONO (185 2225);
DISPLAY INVISIBLE (185 2225);
WIRE 16 -1 (425 2275)(1325 2275);
FORCEPROP 0 LAST SIG_NAME TP_PVDDQ_KLM_PH1_GL_1
J 0
(502 2290);
DISPLAY 0.617021 (502 2290);
PAINT ORANGE (502 2290);
FORCEPROP 2 LASTPROP $XRERR UNIQUE?
J 0
(185 2275);
DISPLAY 0.638298 (185 2275);
PAINT MONO (185 2275);
DISPLAY INVISIBLE (185 2275);
WIRE 16 -1 (2325 2775)(3500 2775);
FORCEPROP 2 LAST SIG_NAME ISENSE_PVDDQ_KLM_PH1_IMON
J 0
(2637 2785);
DISPLAY 0.617021 (2637 2785);
PAINT ORANGE (2637 2785);
WIRE 3 682 (2400 2525)(2500 2525);
WIRE 16 -1 (1025 1925)(1325 1925);
WIRE 16 -1 (1025 2025)(1025 1925);
WIRE 16 -1 (200 2025)(1025 2025);
FORCEPROP 2 LAST SIG_NAME VR_PVDDQ_KLM_PH1_BOOT_R
J 0
(385 2035);
DISPLAY 0.617021 (385 2035);
PAINT ORANGE (385 2035);
FORCEPROP 2 LASTPROP $XRERR UNIQUE?
J 0
(145 2035);
DISPLAY 0.638298 (145 2035);
PAINT MONO (145 2035);
DISPLAY INVISIBLE (145 2035);
WIRE 16 -1 (1150 1825)(1150 2025);
WIRE 16 -1 (1325 2025)(1150 2025);
WIRE 16 -1 (1150 2025)(1150 3100);
WIRE 16 -1 (3475 3100)(1150 3100);
FORCEPROP 2 LAST SIG_NAME VR_PVDDQ_KLM_AIREF1
J 0
(2809 3107);
DISPLAY 0.617021 (2809 3107);
PAINT ORANGE (2809 3107);
WIRE 16 2175 (-625 2650)(250 2650);
WIRE 16 2175 (250 2650)(250 2225);
WIRE 16 2175 (-625 2650)(-625 2225);
WIRE 16 2175 (-625 2225)(250 2225);
WIRE 3 682 (-525 2350)(-525 2600);
WIRE 3 682 (-425 2350)(-525 2350);
WIRE 3 682 (-525 2600)(-425 2600);
WIRE 3 682 (-425 2600)(-425 2350);
WIRE 16 -1 (2825 1850)(2825 1925);
WIRE 16 -1 (3625 1925)(2825 1925);
WIRE 16 -1 (2325 1925)(2825 1925);
FORCEPROP 2 LAST SIG_NAME VR_PVDDQ_KLM_PH1_SW
J 0
(2435 1935);
DISPLAY 0.617021 (2435 1935);
PAINT ORANGE (2435 1935);
FORCEPROP 2 LASTPROP $XRERR UNIQUE?
J 0
(2195 1935);
DISPLAY 0.638298 (2195 1935);
PAINT MONO (2195 1935);
DISPLAY INVISIBLE (2195 1935);
WIRE 16 -1 (3050 2300)(3050 2350);
WIRE 16 -1 (3050 2350)(3575 2350);
WIRE 16 -1 (2325 2350)(2325 2275);
WIRE 16 -1 (2325 2350)(3050 2350);
FORCEPROP 2 LAST SIG_NAME A_TSENSE_PVDDQ_KLM
J 0
(2412 2360);
DISPLAY 0.617021 (2412 2360);
PAINT ORANGE (2412 2360);
WIRE 3 2175 (2950 1975)(3475 1975);
WIRE 3 2175 (3475 2450)(3475 1975);
WIRE 3 2175 (2950 2450)(2950 1975);
WIRE 3 2175 (2950 2450)(3475 2450);
DOT 1 (-1350 425);
DOT 1 (-1900 425);
DOT 1 (-2175 425);
DOT 1 (-2175 -75);
DOT 1 (-1900 -75);
DOT 1 (-1625 425);
DOT 1 (2700 -525);
DOT 1 (1225 325);
DOT 1 (1100 425);
DOT 1 (2925 -625);
DOT 1 (4375 -325);
DOT 1 (-1625 -75);
DOT 1 (-1350 -75);
DOT 1 (-1075 -75);
DOT 1 (-1075 425);
DOT 1 (-825 -75);
DOT 1 (-825 525);
DOT 1 (-425 -75);
DOT 1 (-425 800);
DOT 1 (-75 800);
DOT 1 (1150 -225);
DOT 1 (2700 -575);
DOT 1 (2700 -475);
DOT 1 (2925 -325);
DOT 1 (4300 -325);
DOT 1 (550 800);
DOT 1 (2950 175);
DOT 1 (3050 2350);
DOT 1 (-2250 2200);
DOT 1 (-475 2200);
DOT 1 (-475 3100);
DOT 1 (1150 2025);
DOT 1 (4100 1925);
DOT 1 (-1700 2200);
DOT 1 (-1700 2675);
DOT 1 (-1425 2200);
DOT 1 (-1425 2675);
DOT 1 (-900 2200);
DOT 1 (-900 2775);
DOT 1 (-1175 2200);
DOT 1 (-1975 2200);
DOT 1 (-1975 2675);
DOT 1 (-1175 2675);
DOT 1 (2675 1775);
DOT 1 (600 3100);
DOT 1 (2825 1925);
DOT 1 (2675 1675);
DOT 1 (2675 1725);
DOT 1 (1075 2675);
DOT 1 (1200 2575);
DOT 1 (-100 3100);
DOT 1 (2825 1525);
DOT 1 (4350 1925);
DOT 1 (-1850 2675);
FORCENOTE
TP FAB4 POP CAP ON SS BOM 20170207
(-2150 -50) 0;
DISPLAY LEFT (-2150 -50);
DISPLAY 0.638298 (-2150 -50);
PAINT RED (-2150 -50);
FORCENOTE
TP FAB1 CHANGE PN 0310
(-550 425) 0;
DISPLAY LEFT (-550 425);
DISPLAY 1.021277 (-550 425);
PAINT RED (-550 425);
FORCENOTE
PLACE ON TOP
(-555 -75) 0;
DISPLAY LEFT (-555 -75);
DISPLAY 1.553191 (-555 -75);
PAINT PURPLE (-555 -75);
FORCENOTE
TP FAB1 CO-LAY WITH TI PARTS 11/16
(-325 1475) 0;
DISPLAY LEFT (-325 1475);
DISPLAY 0.851064 (-325 1475);
PAINT RED (-325 1475);
FORCENOTE
TP FAB3-DVT NOPOP FROM SS BOM 20161215
(-2400 1025) 0;
DISPLAY LEFT (-2400 1025);
DISPLAY 1.021277 (-2400 1025);
PAINT RED (-2400 1025);
FORCENOTE
SPOF
(-1030 1600) 0;
DISPLAY LEFT (-1030 1600);
DISPLAY 1.936170 (-1030 1600);
PAINT PURPLE (-1030 1600);
FORCENOTE
TP FAB1 CO-LAY WITH TI PARTS 11/16
(3050 1225) 0;
DISPLAY LEFT (3050 1225);
DISPLAY 0.680851 (3050 1225);
PAINT RED (3050 1225);
FORCENOTE
TP FAB3-DVT NOPOP L1A1 IND FOR SS BOM 20161215
(3575 -125) 0;
DISPLAY LEFT (3575 -125);
DISPLAY 0.510638 (3575 -125);
PAINT RED (3575 -125);
FORCENOTE
TP FAB1 ADD NET NAME 12/04
(3200 -925) 0;
DISPLAY LEFT (3200 -925);
DISPLAY 0.638298 (3200 -925);
PAINT RED (3200 -925);
FORCENOTE
TP FAB1 CHANGE RES TO 1 OHM 0603 0107
(3200 -875) 0;
DISPLAY LEFT (3200 -875);
DISPLAY 0.638298 (3200 -875);
PAINT RED (3200 -875);
FORCENOTE
TP FAB1 CO-LAY WITH TI PARTS 11/16
(2600 -1125) 0;
DISPLAY LEFT (2600 -1125);
DISPLAY 0.851064 (2600 -1125);
PAINT RED (2600 -1125);
FORCENOTE
TP FAB3 CHANGE L1A2 0823
(3500 2050) 0;
DISPLAY LEFT (3500 2050);
DISPLAY 0.808511 (3500 2050);
PAINT RED (3500 2050);
FORCENOTE
TP FAB3 CHANGE L1A1 0823
(3575 -75) 0;
DISPLAY LEFT (3575 -75);
DISPLAY 0.510638 (3575 -75);
PAINT RED (3575 -75);
FORCENOTE
SPOF
(-880 -675) 0;
DISPLAY LEFT (-880 -675);
DISPLAY 1.808511 (-880 -675);
PAINT PURPLE (-880 -675);
FORCENOTE
TP FAB1 CO-LAYOUT WITH TI PARTS 11/16
(-175 -750) 0;
DISPLAY LEFT (-175 -750);
DISPLAY 0.851064 (-175 -750);
PAINT RED (-175 -750);
FORCENOTE
TDA21470
(1675 600) 0;
DISPLAY LEFT (1675 600);
DISPLAY 1.021277 (1675 600);
PAINT SKYBLUE (1675 600);
FORCENOTE
TP FAB1 DEL NET 0309
(2500 250) 0;
DISPLAY LEFT (2500 250);
DISPLAY 1.021277 (2500 250);
PAINT RED (2500 250);
FORCENOTE
TP FAB1 CHANGE L1A1 PN 0122
(3575 -25) 0;
DISPLAY LEFT (3575 -25);
DISPLAY 0.510638 (3575 -25);
PAINT RED (3575 -25);
FORCENOTE
TP FAB1 CO-LAY WITH TI PARTS 11/16
(3325 75) 0;
DISPLAY LEFT (3325 75);
DISPLAY 0.553191 (3325 75);
PAINT RED (3325 75);
FORCENOTE
ROOM = VDDQ_KLM_PWR_VR
(-2505 -1375) 0;
DISPLAY LEFT (-2505 -1375);
DISPLAY 2.319149 (-2505 -1375);
PAINT PURPLE (-2505 -1375);
FORCENOTE
TP FAB1 ADD NET NAME 12/04
(3050 1275) 0;
DISPLAY LEFT (3050 1275);
DISPLAY 0.808511 (3050 1275);
PAINT RED (3050 1275);
FORCENOTE
TP FAB1 CHANGE L1A2 PN 0122
(3500 2100) 0;
DISPLAY LEFT (3500 2100);
DISPLAY 0.808511 (3500 2100);
PAINT RED (3500 2100);
FORCENOTE
TP FAB1 DEL NET 0309
(2525 2500) 0;
DISPLAY LEFT (2525 2500);
DISPLAY 1.021277 (2525 2500);
PAINT RED (2525 2500);
FORCENOTE
TP FAB3-DVT CHANGE L1A2 IND FOR SS BOM 20161215
(3575 1450) 0;
DISPLAY LEFT (3575 1450);
DISPLAY 0.638298 (3575 1450);
PAINT RED (3575 1450);
FORCENOTE
TP FAB1 CO-LAY WITH TI PARTS 11/16
(3475 2175) 0;
DISPLAY LEFT (3475 2175);
DISPLAY 0.851064 (3475 2175);
PAINT RED (3475 2175);
FORCENOTE
TP FAB1 CHANGE RES TO 1 OHM 0603 0107
(3575 1125) 0;
DISPLAY LEFT (3575 1125);
DISPLAY 0.638298 (3575 1125);
PAINT RED (3575 1125);
FORCENOTE
PLACE ON TOP
(-630 2125) 0;
DISPLAY LEFT (-630 2125);
DISPLAY 1.553191 (-630 2125);
PAINT PURPLE (-630 2125);
FORCENOTE
TDA21470
(1650 2850) 0;
DISPLAY LEFT (1650 2850);
DISPLAY 1.021277 (1650 2850);
PAINT SKYBLUE (1650 2850);
FORCENOTE
TP FAB1 CHANGE PN 0310
(-500 2700) 0;
DISPLAY LEFT (-500 2700);
DISPLAY 1.021277 (-500 2700);
PAINT RED (-500 2700);
QUIT
